FILE_TYPE = MACRO_DRAWING;
SET COLOR_WIRE YELLOW;
SET COLOR_PROP ORANGE;
SET COLOR_DOT WHITE;
SET COLOR_ARC YELLOW;
SET COLOR_BODY GREEN;
SET COLOR_NOTE PURPLE;
SET PROP_DISPLAY VALUE;
SET PAGE_NUMBER P97;
FORCEADD OFFPAGE..2
R 2
(-2925 225);
FORCEPROP 2 LAST $XR0 97 
J 0
(-3149 225);
DISPLAY 0.638298 (-3149 225);
PAINT MONO (-3149 225);
FORCEPROP 2 LAST CDS_LIB standard
J 0
(-2925 225);
PAINT MONO (-2925 225);
DISPLAY INVISIBLE (-2925 225);
FORCEPROP 1 LAST OFFPAGE TRUE
J 2
(-3250 100);
DISPLAY 0.872340 (-3250 100);
DISPLAY INVISIBLE (-3250 100);
FORCEPROP 1 LAST COMMENT_BODY TRUE
J 2
(-2880 130);
DISPLAY 0.872340 (-2880 130);
PAINT GREEN (-2880 130);
DISPLAY INVISIBLE (-2880 130);
FORCEPROP 2 LAST PATH I1
J 0
(-2875 300);
DISPLAY 1.021277 (-2875 300);
DISPLAY INVISIBLE (-2875 300);
FORCEADD TAP..1
(-350 2675);
FORCEPROP 3 LASTPIN (-400 2675) SIG_NAME M_H_CPU0_SA_DQ<1>
J 0
(-390 2685);
DISPLAY 0.659574 (-390 2685);
PAINT MONO (-390 2685);
DISPLAY INVISIBLE (-390 2685);
FORCEPROP 1 LASTPIN (-400 2675) BN 1
J 0
(-412 2683);
DISPLAY 0.680851 (-412 2683);
PAINT GREEN (-412 2683);
FORCEPROP 2 LAST CDS_LIB standard
J 0
(-350 2675);
PAINT MONO (-350 2675);
DISPLAY INVISIBLE (-350 2675);
FORCEPROP 1 LAST BODY_TYPE PLUMBING
J 0
(-350 2725);
DISPLAY 0.872340 (-350 2725);
PAINT GREEN (-350 2725);
DISPLAY INVISIBLE (-350 2725);
FORCEPROP 1 LAST HDL_TAP TRUE
J 0
(-25 2550);
DISPLAY 0.872340 (-25 2550);
DISPLAY INVISIBLE (-25 2550);
FORCEPROP 1 LAST PATH I100
J 0
(-352 2675);
DISPLAY 0.872340 (-352 2675);
PAINT GREEN (-352 2675);
DISPLAY INVISIBLE (-352 2675);
FORCEADD TAP..1
(-350 2775);
FORCEPROP 3 LASTPIN (-400 2775) SIG_NAME M_H_CPU0_SA_DQ<3>
J 0
(-390 2785);
DISPLAY 0.659574 (-390 2785);
PAINT MONO (-390 2785);
DISPLAY INVISIBLE (-390 2785);
FORCEPROP 1 LASTPIN (-400 2775) BN 3
J 0
(-412 2783);
DISPLAY 0.680851 (-412 2783);
PAINT GREEN (-412 2783);
FORCEPROP 2 LAST CDS_LIB standard
J 0
(-350 2775);
PAINT MONO (-350 2775);
DISPLAY INVISIBLE (-350 2775);
FORCEPROP 1 LAST BODY_TYPE PLUMBING
J 0
(-350 2825);
DISPLAY 0.872340 (-350 2825);
PAINT GREEN (-350 2825);
DISPLAY INVISIBLE (-350 2825);
FORCEPROP 1 LAST HDL_TAP TRUE
J 0
(-25 2650);
DISPLAY 0.872340 (-25 2650);
DISPLAY INVISIBLE (-25 2650);
FORCEPROP 1 LAST PATH I101
J 0
(-352 2775);
DISPLAY 0.872340 (-352 2775);
PAINT GREEN (-352 2775);
DISPLAY INVISIBLE (-352 2775);
FORCEADD TAP..1
(-350 2825);
FORCEPROP 3 LASTPIN (-400 2825) SIG_NAME M_H_CPU0_SA_DQ<4>
J 0
(-390 2835);
DISPLAY 0.659574 (-390 2835);
PAINT MONO (-390 2835);
DISPLAY INVISIBLE (-390 2835);
FORCEPROP 1 LASTPIN (-400 2825) BN 4
J 0
(-412 2833);
DISPLAY 0.680851 (-412 2833);
PAINT GREEN (-412 2833);
FORCEPROP 2 LAST CDS_LIB standard
J 0
(-350 2825);
PAINT MONO (-350 2825);
DISPLAY INVISIBLE (-350 2825);
FORCEPROP 1 LAST BODY_TYPE PLUMBING
J 0
(-350 2875);
DISPLAY 0.872340 (-350 2875);
PAINT GREEN (-350 2875);
DISPLAY INVISIBLE (-350 2875);
FORCEPROP 1 LAST HDL_TAP TRUE
J 0
(-25 2700);
DISPLAY 0.872340 (-25 2700);
DISPLAY INVISIBLE (-25 2700);
FORCEPROP 1 LAST PATH I102
J 0
(-352 2825);
DISPLAY 0.872340 (-352 2825);
PAINT GREEN (-352 2825);
DISPLAY INVISIBLE (-352 2825);
FORCEADD TAP..1
(-350 2875);
FORCEPROP 3 LASTPIN (-400 2875) SIG_NAME M_H_CPU0_SA_DQ<5>
J 0
(-390 2885);
DISPLAY 0.659574 (-390 2885);
PAINT MONO (-390 2885);
DISPLAY INVISIBLE (-390 2885);
FORCEPROP 1 LASTPIN (-400 2875) BN 5
J 0
(-412 2883);
DISPLAY 0.680851 (-412 2883);
PAINT GREEN (-412 2883);
FORCEPROP 2 LAST CDS_LIB standard
J 0
(-350 2875);
PAINT MONO (-350 2875);
DISPLAY INVISIBLE (-350 2875);
FORCEPROP 1 LAST BODY_TYPE PLUMBING
J 0
(-350 2925);
DISPLAY 0.872340 (-350 2925);
PAINT GREEN (-350 2925);
DISPLAY INVISIBLE (-350 2925);
FORCEPROP 1 LAST HDL_TAP TRUE
J 0
(-25 2750);
DISPLAY 0.872340 (-25 2750);
DISPLAY INVISIBLE (-25 2750);
FORCEPROP 1 LAST PATH I103
J 0
(-352 2875);
DISPLAY 0.872340 (-352 2875);
PAINT GREEN (-352 2875);
DISPLAY INVISIBLE (-352 2875);
FORCEADD OFFPAGE..3
(475 2550);
FORCEPROP 2 LAST $XR1 96 
J 0
(779 2550);
DISPLAY 0.638298 (779 2550);
PAINT MONO (779 2550);
FORCEPROP 2 LAST $XR0 27 
J 0
(689 2550);
DISPLAY 0.638298 (689 2550);
PAINT MONO (689 2550);
FORCEPROP 2 LAST CDS_LIB standard
J 2
(475 2550);
DISPLAY INVISIBLE (475 2550);
FORCEPROP 1 LAST OFFPAGE TRUE
J 0
(800 2425);
DISPLAY 0.872340 (800 2425);
DISPLAY INVISIBLE (800 2425);
FORCEPROP 1 LAST COMMENT_BODY TRUE
J 0
(425 2450);
DISPLAY 0.872340 (425 2450);
PAINT GREEN (425 2450);
DISPLAY INVISIBLE (425 2450);
FORCEPROP 2 LAST PATH I104
J 0
(675 2625);
DISPLAY 1.021277 (675 2625);
DISPLAY INVISIBLE (675 2625);
FORCEADD TAP..1
(-350 2975);
FORCEPROP 3 LASTPIN (-400 2975) SIG_NAME M_H_CPU0_SA_DQ<7>
J 0
(-390 2985);
DISPLAY 0.659574 (-390 2985);
PAINT MONO (-390 2985);
DISPLAY INVISIBLE (-390 2985);
FORCEPROP 1 LASTPIN (-400 2975) BN 7
J 0
(-412 2983);
DISPLAY 0.680851 (-412 2983);
PAINT GREEN (-412 2983);
FORCEPROP 2 LAST CDS_LIB standard
J 0
(-350 2975);
PAINT MONO (-350 2975);
DISPLAY INVISIBLE (-350 2975);
FORCEPROP 1 LAST BODY_TYPE PLUMBING
J 0
(-350 3025);
DISPLAY 0.872340 (-350 3025);
PAINT GREEN (-350 3025);
DISPLAY INVISIBLE (-350 3025);
FORCEPROP 1 LAST HDL_TAP TRUE
J 0
(-25 2850);
DISPLAY 0.872340 (-25 2850);
DISPLAY INVISIBLE (-25 2850);
FORCEPROP 1 LAST PATH I105
J 0
(-352 2975);
DISPLAY 0.872340 (-352 2975);
PAINT GREEN (-352 2975);
DISPLAY INVISIBLE (-352 2975);
FORCEADD TAP..1
(-350 2925);
FORCEPROP 3 LASTPIN (-400 2925) SIG_NAME M_H_CPU0_SA_DQ<6>
J 0
(-390 2935);
DISPLAY 0.659574 (-390 2935);
PAINT MONO (-390 2935);
DISPLAY INVISIBLE (-390 2935);
FORCEPROP 1 LASTPIN (-400 2925) BN 6
J 0
(-412 2933);
DISPLAY 0.680851 (-412 2933);
PAINT GREEN (-412 2933);
FORCEPROP 2 LAST CDS_LIB standard
J 0
(-350 2925);
PAINT MONO (-350 2925);
DISPLAY INVISIBLE (-350 2925);
FORCEPROP 1 LAST BODY_TYPE PLUMBING
J 0
(-350 2975);
DISPLAY 0.872340 (-350 2975);
PAINT GREEN (-350 2975);
DISPLAY INVISIBLE (-350 2975);
FORCEPROP 1 LAST HDL_TAP TRUE
J 0
(-25 2800);
DISPLAY 0.872340 (-25 2800);
DISPLAY INVISIBLE (-25 2800);
FORCEPROP 1 LAST PATH I106
J 0
(-352 2925);
DISPLAY 0.872340 (-352 2925);
PAINT GREEN (-352 2925);
DISPLAY INVISIBLE (-352 2925);
FORCEADD TAP..1
(-350 3025);
FORCEPROP 3 LASTPIN (-400 3025) SIG_NAME M_H_CPU0_SA_DQ<8>
J 0
(-390 3035);
DISPLAY 0.659574 (-390 3035);
PAINT MONO (-390 3035);
DISPLAY INVISIBLE (-390 3035);
FORCEPROP 1 LASTPIN (-400 3025) BN 8
J 0
(-412 3033);
DISPLAY 0.680851 (-412 3033);
PAINT GREEN (-412 3033);
FORCEPROP 2 LAST CDS_LIB standard
J 0
(-350 3025);
PAINT MONO (-350 3025);
DISPLAY INVISIBLE (-350 3025);
FORCEPROP 1 LAST BODY_TYPE PLUMBING
J 0
(-350 3075);
DISPLAY 0.872340 (-350 3075);
PAINT GREEN (-350 3075);
DISPLAY INVISIBLE (-350 3075);
FORCEPROP 1 LAST HDL_TAP TRUE
J 0
(-25 2900);
DISPLAY 0.872340 (-25 2900);
DISPLAY INVISIBLE (-25 2900);
FORCEPROP 1 LAST PATH I107
J 0
(-352 3025);
DISPLAY 0.872340 (-352 3025);
PAINT GREEN (-352 3025);
DISPLAY INVISIBLE (-352 3025);
FORCEADD TAP..1
(-350 3125);
FORCEPROP 3 LASTPIN (-400 3125) SIG_NAME M_H_CPU0_SA_DQ<10>
J 0
(-390 3135);
DISPLAY 0.659574 (-390 3135);
PAINT MONO (-390 3135);
DISPLAY INVISIBLE (-390 3135);
FORCEPROP 1 LASTPIN (-400 3125) BN 10
J 0
(-412 3133);
DISPLAY 0.680851 (-412 3133);
PAINT GREEN (-412 3133);
FORCEPROP 2 LAST CDS_LIB standard
J 0
(-350 3125);
PAINT MONO (-350 3125);
DISPLAY INVISIBLE (-350 3125);
FORCEPROP 1 LAST BODY_TYPE PLUMBING
J 0
(-350 3175);
DISPLAY 0.872340 (-350 3175);
PAINT GREEN (-350 3175);
DISPLAY INVISIBLE (-350 3175);
FORCEPROP 1 LAST HDL_TAP TRUE
J 0
(-25 3000);
DISPLAY 0.872340 (-25 3000);
DISPLAY INVISIBLE (-25 3000);
FORCEPROP 1 LAST PATH I108
J 0
(-352 3125);
DISPLAY 0.872340 (-352 3125);
PAINT GREEN (-352 3125);
DISPLAY INVISIBLE (-352 3125);
FORCEADD TAP..1
(-350 3075);
FORCEPROP 3 LASTPIN (-400 3075) SIG_NAME M_H_CPU0_SA_DQ<9>
J 0
(-390 3085);
DISPLAY 0.659574 (-390 3085);
PAINT MONO (-390 3085);
DISPLAY INVISIBLE (-390 3085);
FORCEPROP 1 LASTPIN (-400 3075) BN 9
J 0
(-412 3083);
DISPLAY 0.680851 (-412 3083);
PAINT GREEN (-412 3083);
FORCEPROP 2 LAST CDS_LIB standard
J 0
(-350 3075);
PAINT MONO (-350 3075);
DISPLAY INVISIBLE (-350 3075);
FORCEPROP 1 LAST BODY_TYPE PLUMBING
J 0
(-350 3125);
DISPLAY 0.872340 (-350 3125);
PAINT GREEN (-350 3125);
DISPLAY INVISIBLE (-350 3125);
FORCEPROP 1 LAST HDL_TAP TRUE
J 0
(-25 2950);
DISPLAY 0.872340 (-25 2950);
DISPLAY INVISIBLE (-25 2950);
FORCEPROP 1 LAST PATH I109
J 0
(-352 3075);
DISPLAY 0.872340 (-352 3075);
PAINT GREEN (-352 3075);
DISPLAY INVISIBLE (-352 3075);
FORCEADD OFFPAGE..1
(-2825 1650);
FORCEPROP 2 LAST $XR0 97 
J 0
(-3076 1650);
DISPLAY 0.638298 (-3076 1650);
PAINT MONO (-3076 1650);
FORCEPROP 2 LAST CDS_LIB standard
J 0
(-2825 1650);
PAINT MONO (-2825 1650);
DISPLAY INVISIBLE (-2825 1650);
FORCEPROP 1 LAST OFFPAGE TRUE
J 0
(-2500 1525);
DISPLAY 0.872340 (-2500 1525);
DISPLAY INVISIBLE (-2500 1525);
FORCEPROP 1 LAST COMMENT_BODY TRUE
J 0
(-2700 1550);
DISPLAY 0.872340 (-2700 1550);
PAINT GREEN (-2700 1550);
DISPLAY INVISIBLE (-2700 1550);
FORCEPROP 2 LAST PATH I11
J 0
(-2775 1725);
DISPLAY 1.021277 (-2775 1725);
DISPLAY INVISIBLE (-2775 1725);
FORCEADD TAP..1
(-350 3225);
FORCEPROP 3 LASTPIN (-400 3225) SIG_NAME M_H_CPU0_SA_DQ<12>
J 0
(-390 3235);
DISPLAY 0.659574 (-390 3235);
PAINT MONO (-390 3235);
DISPLAY INVISIBLE (-390 3235);
FORCEPROP 1 LASTPIN (-400 3225) BN 12
J 0
(-412 3233);
DISPLAY 0.680851 (-412 3233);
PAINT GREEN (-412 3233);
FORCEPROP 2 LAST CDS_LIB standard
J 0
(-350 3225);
PAINT MONO (-350 3225);
DISPLAY INVISIBLE (-350 3225);
FORCEPROP 1 LAST BODY_TYPE PLUMBING
J 0
(-350 3275);
DISPLAY 0.872340 (-350 3275);
PAINT GREEN (-350 3275);
DISPLAY INVISIBLE (-350 3275);
FORCEPROP 1 LAST HDL_TAP TRUE
J 0
(-25 3100);
DISPLAY 0.872340 (-25 3100);
DISPLAY INVISIBLE (-25 3100);
FORCEPROP 1 LAST PATH I110
J 0
(-352 3225);
DISPLAY 0.872340 (-352 3225);
PAINT GREEN (-352 3225);
DISPLAY INVISIBLE (-352 3225);
FORCEADD TAP..1
(-350 3175);
FORCEPROP 3 LASTPIN (-400 3175) SIG_NAME M_H_CPU0_SA_DQ<11>
J 0
(-390 3185);
DISPLAY 0.659574 (-390 3185);
PAINT MONO (-390 3185);
DISPLAY INVISIBLE (-390 3185);
FORCEPROP 1 LASTPIN (-400 3175) BN 11
J 0
(-412 3183);
DISPLAY 0.680851 (-412 3183);
PAINT GREEN (-412 3183);
FORCEPROP 2 LAST CDS_LIB standard
J 0
(-350 3175);
PAINT MONO (-350 3175);
DISPLAY INVISIBLE (-350 3175);
FORCEPROP 1 LAST BODY_TYPE PLUMBING
J 0
(-350 3225);
DISPLAY 0.872340 (-350 3225);
PAINT GREEN (-350 3225);
DISPLAY INVISIBLE (-350 3225);
FORCEPROP 1 LAST HDL_TAP TRUE
J 0
(-25 3050);
DISPLAY 0.872340 (-25 3050);
DISPLAY INVISIBLE (-25 3050);
FORCEPROP 1 LAST PATH I111
J 0
(-352 3175);
DISPLAY 0.872340 (-352 3175);
PAINT GREEN (-352 3175);
DISPLAY INVISIBLE (-352 3175);
FORCEADD TAP..1
(-350 3275);
FORCEPROP 3 LASTPIN (-400 3275) SIG_NAME M_H_CPU0_SA_DQ<13>
J 0
(-390 3285);
DISPLAY 0.659574 (-390 3285);
PAINT MONO (-390 3285);
DISPLAY INVISIBLE (-390 3285);
FORCEPROP 1 LASTPIN (-400 3275) BN 13
J 0
(-412 3283);
DISPLAY 0.680851 (-412 3283);
PAINT GREEN (-412 3283);
FORCEPROP 2 LAST CDS_LIB standard
J 0
(-350 3275);
PAINT MONO (-350 3275);
DISPLAY INVISIBLE (-350 3275);
FORCEPROP 1 LAST BODY_TYPE PLUMBING
J 0
(-350 3325);
DISPLAY 0.872340 (-350 3325);
PAINT GREEN (-350 3325);
DISPLAY INVISIBLE (-350 3325);
FORCEPROP 1 LAST HDL_TAP TRUE
J 0
(-25 3150);
DISPLAY 0.872340 (-25 3150);
DISPLAY INVISIBLE (-25 3150);
FORCEPROP 1 LAST PATH I112
J 0
(-352 3275);
DISPLAY 0.872340 (-352 3275);
PAINT GREEN (-352 3275);
DISPLAY INVISIBLE (-352 3275);
FORCEADD TAP..1
(-350 3375);
FORCEPROP 3 LASTPIN (-400 3375) SIG_NAME M_H_CPU0_SA_DQ<15>
J 0
(-390 3385);
DISPLAY 0.659574 (-390 3385);
PAINT MONO (-390 3385);
DISPLAY INVISIBLE (-390 3385);
FORCEPROP 1 LASTPIN (-400 3375) BN 15
J 0
(-412 3383);
DISPLAY 0.680851 (-412 3383);
PAINT GREEN (-412 3383);
FORCEPROP 2 LAST CDS_LIB standard
J 0
(-350 3375);
PAINT MONO (-350 3375);
DISPLAY INVISIBLE (-350 3375);
FORCEPROP 1 LAST BODY_TYPE PLUMBING
J 0
(-350 3425);
DISPLAY 0.872340 (-350 3425);
PAINT GREEN (-350 3425);
DISPLAY INVISIBLE (-350 3425);
FORCEPROP 1 LAST HDL_TAP TRUE
J 0
(-25 3250);
DISPLAY 0.872340 (-25 3250);
DISPLAY INVISIBLE (-25 3250);
FORCEPROP 1 LAST PATH I113
J 0
(-352 3375);
DISPLAY 0.872340 (-352 3375);
PAINT GREEN (-352 3375);
DISPLAY INVISIBLE (-352 3375);
FORCEADD TAP..1
(-350 3325);
FORCEPROP 3 LASTPIN (-400 3325) SIG_NAME M_H_CPU0_SA_DQ<14>
J 0
(-390 3335);
DISPLAY 0.659574 (-390 3335);
PAINT MONO (-390 3335);
DISPLAY INVISIBLE (-390 3335);
FORCEPROP 1 LASTPIN (-400 3325) BN 14
J 0
(-412 3333);
DISPLAY 0.680851 (-412 3333);
PAINT GREEN (-412 3333);
FORCEPROP 2 LAST CDS_LIB standard
J 0
(-350 3325);
PAINT MONO (-350 3325);
DISPLAY INVISIBLE (-350 3325);
FORCEPROP 1 LAST BODY_TYPE PLUMBING
J 0
(-350 3375);
DISPLAY 0.872340 (-350 3375);
PAINT GREEN (-350 3375);
DISPLAY INVISIBLE (-350 3375);
FORCEPROP 1 LAST HDL_TAP TRUE
J 0
(-25 3200);
DISPLAY 0.872340 (-25 3200);
DISPLAY INVISIBLE (-25 3200);
FORCEPROP 1 LAST PATH I114
J 0
(-352 3325);
DISPLAY 0.872340 (-352 3325);
PAINT GREEN (-352 3325);
DISPLAY INVISIBLE (-352 3325);
FORCEADD TAP..1
(-350 3425);
FORCEPROP 3 LASTPIN (-400 3425) SIG_NAME M_H_CPU0_SA_DQ<16>
J 0
(-390 3435);
DISPLAY 0.659574 (-390 3435);
PAINT MONO (-390 3435);
DISPLAY INVISIBLE (-390 3435);
FORCEPROP 1 LASTPIN (-400 3425) BN 16
J 0
(-412 3433);
DISPLAY 0.680851 (-412 3433);
PAINT GREEN (-412 3433);
FORCEPROP 2 LAST CDS_LIB standard
J 0
(-350 3425);
PAINT MONO (-350 3425);
DISPLAY INVISIBLE (-350 3425);
FORCEPROP 1 LAST BODY_TYPE PLUMBING
J 0
(-350 3475);
DISPLAY 0.872340 (-350 3475);
PAINT GREEN (-350 3475);
DISPLAY INVISIBLE (-350 3475);
FORCEPROP 1 LAST HDL_TAP TRUE
J 0
(-25 3300);
DISPLAY 0.872340 (-25 3300);
DISPLAY INVISIBLE (-25 3300);
FORCEPROP 1 LAST PATH I115
J 0
(-352 3425);
DISPLAY 0.872340 (-352 3425);
PAINT GREEN (-352 3425);
DISPLAY INVISIBLE (-352 3425);
FORCEADD TAP..1
(-350 3525);
FORCEPROP 3 LASTPIN (-400 3525) SIG_NAME M_H_CPU0_SA_DQ<18>
J 0
(-390 3535);
DISPLAY 0.659574 (-390 3535);
PAINT MONO (-390 3535);
DISPLAY INVISIBLE (-390 3535);
FORCEPROP 1 LASTPIN (-400 3525) BN 18
J 0
(-412 3533);
DISPLAY 0.680851 (-412 3533);
PAINT GREEN (-412 3533);
FORCEPROP 2 LAST CDS_LIB standard
J 0
(-350 3525);
PAINT MONO (-350 3525);
DISPLAY INVISIBLE (-350 3525);
FORCEPROP 1 LAST BODY_TYPE PLUMBING
J 0
(-350 3575);
DISPLAY 0.872340 (-350 3575);
PAINT GREEN (-350 3575);
DISPLAY INVISIBLE (-350 3575);
FORCEPROP 1 LAST HDL_TAP TRUE
J 0
(-25 3400);
DISPLAY 0.872340 (-25 3400);
DISPLAY INVISIBLE (-25 3400);
FORCEPROP 1 LAST PATH I116
J 0
(-352 3525);
DISPLAY 0.872340 (-352 3525);
PAINT GREEN (-352 3525);
DISPLAY INVISIBLE (-352 3525);
FORCEADD TAP..1
(-350 3475);
FORCEPROP 3 LASTPIN (-400 3475) SIG_NAME M_H_CPU0_SA_DQ<17>
J 0
(-390 3485);
DISPLAY 0.659574 (-390 3485);
PAINT MONO (-390 3485);
DISPLAY INVISIBLE (-390 3485);
FORCEPROP 1 LASTPIN (-400 3475) BN 17
J 0
(-412 3483);
DISPLAY 0.680851 (-412 3483);
PAINT GREEN (-412 3483);
FORCEPROP 2 LAST CDS_LIB standard
J 0
(-350 3475);
PAINT MONO (-350 3475);
DISPLAY INVISIBLE (-350 3475);
FORCEPROP 1 LAST BODY_TYPE PLUMBING
J 0
(-350 3525);
DISPLAY 0.872340 (-350 3525);
PAINT GREEN (-350 3525);
DISPLAY INVISIBLE (-350 3525);
FORCEPROP 1 LAST HDL_TAP TRUE
J 0
(-25 3350);
DISPLAY 0.872340 (-25 3350);
DISPLAY INVISIBLE (-25 3350);
FORCEPROP 1 LAST PATH I117
J 0
(-352 3475);
DISPLAY 0.872340 (-352 3475);
PAINT GREEN (-352 3475);
DISPLAY INVISIBLE (-352 3475);
FORCEADD TAP..1
(-350 3625);
FORCEPROP 3 LASTPIN (-400 3625) SIG_NAME M_H_CPU0_SA_DQ<20>
J 0
(-390 3635);
DISPLAY 0.659574 (-390 3635);
PAINT MONO (-390 3635);
DISPLAY INVISIBLE (-390 3635);
FORCEPROP 1 LASTPIN (-400 3625) BN 20
J 0
(-412 3633);
DISPLAY 0.680851 (-412 3633);
PAINT GREEN (-412 3633);
FORCEPROP 2 LAST CDS_LIB standard
J 0
(-350 3625);
PAINT MONO (-350 3625);
DISPLAY INVISIBLE (-350 3625);
FORCEPROP 1 LAST BODY_TYPE PLUMBING
J 0
(-350 3675);
DISPLAY 0.872340 (-350 3675);
PAINT GREEN (-350 3675);
DISPLAY INVISIBLE (-350 3675);
FORCEPROP 1 LAST HDL_TAP TRUE
J 0
(-25 3500);
DISPLAY 0.872340 (-25 3500);
DISPLAY INVISIBLE (-25 3500);
FORCEPROP 1 LAST PATH I118
J 0
(-352 3625);
DISPLAY 0.872340 (-352 3625);
PAINT GREEN (-352 3625);
DISPLAY INVISIBLE (-352 3625);
FORCEADD TAP..1
(-350 3575);
FORCEPROP 3 LASTPIN (-400 3575) SIG_NAME M_H_CPU0_SA_DQ<19>
J 0
(-390 3585);
DISPLAY 0.659574 (-390 3585);
PAINT MONO (-390 3585);
DISPLAY INVISIBLE (-390 3585);
FORCEPROP 1 LASTPIN (-400 3575) BN 19
J 0
(-412 3583);
DISPLAY 0.680851 (-412 3583);
PAINT GREEN (-412 3583);
FORCEPROP 2 LAST CDS_LIB standard
J 0
(-350 3575);
PAINT MONO (-350 3575);
DISPLAY INVISIBLE (-350 3575);
FORCEPROP 1 LAST BODY_TYPE PLUMBING
J 0
(-350 3625);
DISPLAY 0.872340 (-350 3625);
PAINT GREEN (-350 3625);
DISPLAY INVISIBLE (-350 3625);
FORCEPROP 1 LAST HDL_TAP TRUE
J 0
(-25 3450);
DISPLAY 0.872340 (-25 3450);
DISPLAY INVISIBLE (-25 3450);
FORCEPROP 1 LAST PATH I119
J 0
(-352 3575);
DISPLAY 0.872340 (-352 3575);
PAINT GREEN (-352 3575);
DISPLAY INVISIBLE (-352 3575);
FORCEADD OFFPAGE..1
(-2925 1900);
FORCEPROP 2 LAST $XR3 96 
J 0
(-3177 1864);
DISPLAY 0.638298 (-3177 1864);
PAINT MONO (-3177 1864);
FORCEPROP 2 LAST $XR2 95 
J 0
(-3357 1900);
DISPLAY 0.638298 (-3357 1900);
PAINT MONO (-3357 1900);
FORCEPROP 2 LAST $XR1 94 
J 0
(-3267 1900);
DISPLAY 0.638298 (-3267 1900);
PAINT MONO (-3267 1900);
FORCEPROP 2 LAST $XR0 129 
J 0
(-3177 1900);
DISPLAY 0.638298 (-3177 1900);
PAINT MONO (-3177 1900);
FORCEPROP 2 LAST CDS_LIB standard
J 0
(-2925 1900);
PAINT MONO (-2925 1900);
DISPLAY INVISIBLE (-2925 1900);
FORCEPROP 1 LAST OFFPAGE TRUE
J 0
(-2600 1775);
DISPLAY 0.872340 (-2600 1775);
DISPLAY INVISIBLE (-2600 1775);
FORCEPROP 1 LAST COMMENT_BODY TRUE
J 0
(-2800 1800);
DISPLAY 0.872340 (-2800 1800);
PAINT GREEN (-2800 1800);
DISPLAY INVISIBLE (-2800 1800);
FORCEPROP 2 LAST PATH I12
J 0
(-2875 1975);
DISPLAY 1.021277 (-2875 1975);
DISPLAY INVISIBLE (-2875 1975);
FORCEADD TAP..1
(-350 3725);
FORCEPROP 3 LASTPIN (-400 3725) SIG_NAME M_H_CPU0_SA_DQ<22>
J 0
(-390 3735);
DISPLAY 0.659574 (-390 3735);
PAINT MONO (-390 3735);
DISPLAY INVISIBLE (-390 3735);
FORCEPROP 1 LASTPIN (-400 3725) BN 22
J 0
(-412 3733);
DISPLAY 0.680851 (-412 3733);
PAINT GREEN (-412 3733);
FORCEPROP 2 LAST CDS_LIB standard
J 0
(-350 3725);
DISPLAY INVISIBLE (-350 3725);
FORCEPROP 1 LAST BODY_TYPE PLUMBING
J 0
(-350 3775);
DISPLAY 0.872340 (-350 3775);
PAINT GREEN (-350 3775);
DISPLAY INVISIBLE (-350 3775);
FORCEPROP 1 LAST HDL_TAP TRUE
J 0
(-25 3600);
DISPLAY 0.872340 (-25 3600);
DISPLAY INVISIBLE (-25 3600);
FORCEPROP 1 LAST PATH I120
J 0
(-352 3725);
DISPLAY 0.872340 (-352 3725);
PAINT GREEN (-352 3725);
DISPLAY INVISIBLE (-352 3725);
FORCEADD TAP..1
(-350 3675);
FORCEPROP 3 LASTPIN (-400 3675) SIG_NAME M_H_CPU0_SA_DQ<21>
J 0
(-390 3685);
DISPLAY 0.659574 (-390 3685);
PAINT MONO (-390 3685);
DISPLAY INVISIBLE (-390 3685);
FORCEPROP 1 LASTPIN (-400 3675) BN 21
J 0
(-412 3683);
DISPLAY 0.680851 (-412 3683);
PAINT GREEN (-412 3683);
FORCEPROP 2 LAST CDS_LIB standard
J 0
(-350 3675);
PAINT MONO (-350 3675);
DISPLAY INVISIBLE (-350 3675);
FORCEPROP 1 LAST BODY_TYPE PLUMBING
J 0
(-350 3725);
DISPLAY 0.872340 (-350 3725);
PAINT GREEN (-350 3725);
DISPLAY INVISIBLE (-350 3725);
FORCEPROP 1 LAST HDL_TAP TRUE
J 0
(-25 3550);
DISPLAY 0.872340 (-25 3550);
DISPLAY INVISIBLE (-25 3550);
FORCEPROP 1 LAST PATH I121
J 0
(-352 3675);
DISPLAY 0.872340 (-352 3675);
PAINT GREEN (-352 3675);
DISPLAY INVISIBLE (-352 3675);
FORCEADD TAP..1
(-350 3775);
FORCEPROP 3 LASTPIN (-400 3775) SIG_NAME M_H_CPU0_SA_DQ<23>
J 0
(-390 3785);
DISPLAY 0.659574 (-390 3785);
PAINT MONO (-390 3785);
DISPLAY INVISIBLE (-390 3785);
FORCEPROP 1 LASTPIN (-400 3775) BN 23
J 0
(-412 3783);
DISPLAY 0.680851 (-412 3783);
PAINT GREEN (-412 3783);
FORCEPROP 2 LAST CDS_LIB standard
J 0
(-350 3775);
DISPLAY INVISIBLE (-350 3775);
FORCEPROP 1 LAST BODY_TYPE PLUMBING
J 0
(-350 3825);
DISPLAY 0.872340 (-350 3825);
PAINT GREEN (-350 3825);
DISPLAY INVISIBLE (-350 3825);
FORCEPROP 1 LAST HDL_TAP TRUE
J 0
(-25 3650);
DISPLAY 0.872340 (-25 3650);
DISPLAY INVISIBLE (-25 3650);
FORCEPROP 1 LAST PATH I122
J 0
(-352 3775);
DISPLAY 0.872340 (-352 3775);
PAINT GREEN (-352 3775);
DISPLAY INVISIBLE (-352 3775);
FORCEADD TAP..1
(-350 3875);
FORCEPROP 3 LASTPIN (-400 3875) SIG_NAME M_H_CPU0_SA_DQ<25>
J 0
(-390 3885);
DISPLAY 0.659574 (-390 3885);
PAINT MONO (-390 3885);
DISPLAY INVISIBLE (-390 3885);
FORCEPROP 1 LASTPIN (-400 3875) BN 25
J 0
(-412 3883);
DISPLAY 0.680851 (-412 3883);
PAINT GREEN (-412 3883);
FORCEPROP 2 LAST CDS_LIB standard
J 0
(-350 3875);
DISPLAY INVISIBLE (-350 3875);
FORCEPROP 1 LAST BODY_TYPE PLUMBING
J 0
(-350 3925);
DISPLAY 0.872340 (-350 3925);
PAINT GREEN (-350 3925);
DISPLAY INVISIBLE (-350 3925);
FORCEPROP 1 LAST HDL_TAP TRUE
J 0
(-25 3750);
DISPLAY 0.872340 (-25 3750);
DISPLAY INVISIBLE (-25 3750);
FORCEPROP 1 LAST PATH I123
J 0
(-352 3875);
DISPLAY 0.872340 (-352 3875);
PAINT GREEN (-352 3875);
DISPLAY INVISIBLE (-352 3875);
FORCEADD TAP..1
(-350 3825);
FORCEPROP 3 LASTPIN (-400 3825) SIG_NAME M_H_CPU0_SA_DQ<24>
J 0
(-390 3835);
DISPLAY 0.659574 (-390 3835);
PAINT MONO (-390 3835);
DISPLAY INVISIBLE (-390 3835);
FORCEPROP 1 LASTPIN (-400 3825) BN 24
J 0
(-412 3833);
DISPLAY 0.680851 (-412 3833);
PAINT GREEN (-412 3833);
FORCEPROP 2 LAST CDS_LIB standard
J 0
(-350 3825);
DISPLAY INVISIBLE (-350 3825);
FORCEPROP 1 LAST BODY_TYPE PLUMBING
J 0
(-350 3875);
DISPLAY 0.872340 (-350 3875);
PAINT GREEN (-350 3875);
DISPLAY INVISIBLE (-350 3875);
FORCEPROP 1 LAST HDL_TAP TRUE
J 0
(-25 3700);
DISPLAY 0.872340 (-25 3700);
DISPLAY INVISIBLE (-25 3700);
FORCEPROP 1 LAST PATH I124
J 0
(-352 3825);
DISPLAY 0.872340 (-352 3825);
PAINT GREEN (-352 3825);
DISPLAY INVISIBLE (-352 3825);
FORCEADD TAP..1
(-350 3925);
FORCEPROP 3 LASTPIN (-400 3925) SIG_NAME M_H_CPU0_SA_DQ<26>
J 0
(-390 3935);
DISPLAY 0.659574 (-390 3935);
PAINT MONO (-390 3935);
DISPLAY INVISIBLE (-390 3935);
FORCEPROP 1 LASTPIN (-400 3925) BN 26
J 0
(-412 3933);
DISPLAY 0.680851 (-412 3933);
PAINT GREEN (-412 3933);
FORCEPROP 2 LAST CDS_LIB standard
J 0
(-350 3925);
DISPLAY INVISIBLE (-350 3925);
FORCEPROP 1 LAST BODY_TYPE PLUMBING
J 0
(-350 3975);
DISPLAY 0.872340 (-350 3975);
PAINT GREEN (-350 3975);
DISPLAY INVISIBLE (-350 3975);
FORCEPROP 1 LAST HDL_TAP TRUE
J 0
(-25 3800);
DISPLAY 0.872340 (-25 3800);
DISPLAY INVISIBLE (-25 3800);
FORCEPROP 1 LAST PATH I125
J 0
(-352 3925);
DISPLAY 0.872340 (-352 3925);
PAINT GREEN (-352 3925);
DISPLAY INVISIBLE (-352 3925);
FORCEADD TAP..1
(-350 4025);
FORCEPROP 3 LASTPIN (-400 4025) SIG_NAME M_H_CPU0_SA_DQ<28>
J 0
(-390 4035);
DISPLAY 0.659574 (-390 4035);
PAINT MONO (-390 4035);
DISPLAY INVISIBLE (-390 4035);
FORCEPROP 1 LASTPIN (-400 4025) BN 28
J 0
(-412 4033);
DISPLAY 0.680851 (-412 4033);
PAINT GREEN (-412 4033);
FORCEPROP 2 LAST CDS_LIB standard
J 0
(-350 4025);
DISPLAY INVISIBLE (-350 4025);
FORCEPROP 1 LAST BODY_TYPE PLUMBING
J 0
(-350 4075);
DISPLAY 0.872340 (-350 4075);
PAINT GREEN (-350 4075);
DISPLAY INVISIBLE (-350 4075);
FORCEPROP 1 LAST HDL_TAP TRUE
J 0
(-25 3900);
DISPLAY 0.872340 (-25 3900);
DISPLAY INVISIBLE (-25 3900);
FORCEPROP 1 LAST PATH I126
J 0
(-352 4025);
DISPLAY 0.872340 (-352 4025);
PAINT GREEN (-352 4025);
DISPLAY INVISIBLE (-352 4025);
FORCEADD TAP..1
(-350 3975);
FORCEPROP 3 LASTPIN (-400 3975) SIG_NAME M_H_CPU0_SA_DQ<27>
J 0
(-390 3985);
DISPLAY 0.659574 (-390 3985);
PAINT MONO (-390 3985);
DISPLAY INVISIBLE (-390 3985);
FORCEPROP 1 LASTPIN (-400 3975) BN 27
J 0
(-412 3983);
DISPLAY 0.680851 (-412 3983);
PAINT GREEN (-412 3983);
FORCEPROP 2 LAST CDS_LIB standard
J 0
(-350 3975);
DISPLAY INVISIBLE (-350 3975);
FORCEPROP 1 LAST BODY_TYPE PLUMBING
J 0
(-350 4025);
DISPLAY 0.872340 (-350 4025);
PAINT GREEN (-350 4025);
DISPLAY INVISIBLE (-350 4025);
FORCEPROP 1 LAST HDL_TAP TRUE
J 0
(-25 3850);
DISPLAY 0.872340 (-25 3850);
DISPLAY INVISIBLE (-25 3850);
FORCEPROP 1 LAST PATH I127
J 0
(-352 3975);
DISPLAY 0.872340 (-352 3975);
PAINT GREEN (-352 3975);
DISPLAY INVISIBLE (-352 3975);
FORCEADD TAP..1
(-350 4175);
FORCEPROP 3 LASTPIN (-400 4175) SIG_NAME M_H_CPU0_SA_DQ<31>
J 0
(-390 4185);
DISPLAY 0.659574 (-390 4185);
PAINT MONO (-390 4185);
DISPLAY INVISIBLE (-390 4185);
FORCEPROP 1 LASTPIN (-400 4175) BN 31
J 0
(-412 4183);
DISPLAY 0.680851 (-412 4183);
PAINT GREEN (-412 4183);
FORCEPROP 2 LAST CDS_LIB standard
J 0
(-350 4175);
DISPLAY INVISIBLE (-350 4175);
FORCEPROP 1 LAST BODY_TYPE PLUMBING
J 0
(-350 4225);
DISPLAY 0.872340 (-350 4225);
PAINT GREEN (-350 4225);
DISPLAY INVISIBLE (-350 4225);
FORCEPROP 1 LAST HDL_TAP TRUE
J 0
(-25 4050);
DISPLAY 0.872340 (-25 4050);
DISPLAY INVISIBLE (-25 4050);
FORCEPROP 1 LAST PATH I128
J 0
(-352 4175);
DISPLAY 0.872340 (-352 4175);
PAINT GREEN (-352 4175);
DISPLAY INVISIBLE (-352 4175);
FORCEADD TAP..1
(-350 4075);
FORCEPROP 3 LASTPIN (-400 4075) SIG_NAME M_H_CPU0_SA_DQ<29>
J 0
(-390 4085);
DISPLAY 0.659574 (-390 4085);
PAINT MONO (-390 4085);
DISPLAY INVISIBLE (-390 4085);
FORCEPROP 1 LASTPIN (-400 4075) BN 29
J 0
(-412 4083);
DISPLAY 0.680851 (-412 4083);
PAINT GREEN (-412 4083);
FORCEPROP 2 LAST CDS_LIB standard
J 0
(-350 4075);
DISPLAY INVISIBLE (-350 4075);
FORCEPROP 1 LAST BODY_TYPE PLUMBING
J 0
(-350 4125);
DISPLAY 0.872340 (-350 4125);
PAINT GREEN (-350 4125);
DISPLAY INVISIBLE (-350 4125);
FORCEPROP 1 LAST HDL_TAP TRUE
J 0
(-25 3950);
DISPLAY 0.872340 (-25 3950);
DISPLAY INVISIBLE (-25 3950);
FORCEPROP 1 LAST PATH I129
J 0
(-352 4075);
DISPLAY 0.872340 (-352 4075);
PAINT GREEN (-352 4075);
DISPLAY INVISIBLE (-352 4075);
FORCEADD OFFPAGE..3
R 2
(-2925 2350);
FORCEPROP 2 LAST $XR1 96 
J 0
(-3264 2350);
DISPLAY 0.638298 (-3264 2350);
PAINT MONO (-3264 2350);
FORCEPROP 2 LAST $XR0 27 
J 0
(-3174 2350);
DISPLAY 0.638298 (-3174 2350);
PAINT MONO (-3174 2350);
FORCEPROP 2 LAST CDS_LIB standard
J 0
(-2925 2350);
PAINT MONO (-2925 2350);
DISPLAY INVISIBLE (-2925 2350);
FORCEPROP 1 LAST OFFPAGE TRUE
J 2
(-3250 2225);
DISPLAY 0.872340 (-3250 2225);
DISPLAY INVISIBLE (-3250 2225);
FORCEPROP 1 LAST COMMENT_BODY TRUE
J 2
(-2875 2250);
DISPLAY 0.872340 (-2875 2250);
PAINT GREEN (-2875 2250);
DISPLAY INVISIBLE (-2875 2250);
FORCEPROP 2 LAST PATH I13
J 0
(-2875 2425);
DISPLAY 1.021277 (-2875 2425);
DISPLAY INVISIBLE (-2875 2425);
FORCEADD TAP..1
(-350 4125);
FORCEPROP 3 LASTPIN (-400 4125) SIG_NAME M_H_CPU0_SA_DQ<30>
J 0
(-390 4135);
DISPLAY 0.659574 (-390 4135);
PAINT MONO (-390 4135);
DISPLAY INVISIBLE (-390 4135);
FORCEPROP 1 LASTPIN (-400 4125) BN 30
J 0
(-412 4133);
DISPLAY 0.680851 (-412 4133);
PAINT GREEN (-412 4133);
FORCEPROP 2 LAST CDS_LIB standard
J 0
(-350 4125);
DISPLAY INVISIBLE (-350 4125);
FORCEPROP 1 LAST BODY_TYPE PLUMBING
J 0
(-350 4175);
DISPLAY 0.872340 (-350 4175);
PAINT GREEN (-350 4175);
DISPLAY INVISIBLE (-350 4175);
FORCEPROP 1 LAST HDL_TAP TRUE
J 0
(-25 4000);
DISPLAY 0.872340 (-25 4000);
DISPLAY INVISIBLE (-25 4000);
FORCEPROP 1 LAST PATH I130
J 0
(-352 4125);
DISPLAY 0.872340 (-352 4125);
PAINT GREEN (-352 4125);
DISPLAY INVISIBLE (-352 4125);
FORCEADD OFFPAGE..3
(475 4200);
FORCEPROP 2 LAST $XR1 96 
J 0
(779 4200);
DISPLAY 0.638298 (779 4200);
PAINT MONO (779 4200);
FORCEPROP 2 LAST $XR0 27 
J 0
(689 4200);
DISPLAY 0.638298 (689 4200);
PAINT MONO (689 4200);
FORCEPROP 2 LAST CDS_LIB standard
J 2
(475 4200);
DISPLAY INVISIBLE (475 4200);
FORCEPROP 1 LAST OFFPAGE TRUE
J 0
(800 4075);
DISPLAY 0.872340 (800 4075);
DISPLAY INVISIBLE (800 4075);
FORCEPROP 1 LAST COMMENT_BODY TRUE
J 0
(425 4100);
DISPLAY 0.872340 (425 4100);
PAINT GREEN (425 4100);
DISPLAY INVISIBLE (425 4100);
FORCEPROP 2 LAST PATH I131
J 0
(675 4275);
DISPLAY 1.021277 (675 4275);
DISPLAY INVISIBLE (675 4275);
FORCEADD TAP..1
(2400 2225);
FORCEPROP 3 LASTPIN (2350 2225) SIG_NAME M_H_CPU0_SB_DQS_DP<0>
J 0
(2360 2235);
DISPLAY 0.659574 (2360 2235);
PAINT MONO (2360 2235);
DISPLAY INVISIBLE (2360 2235);
FORCEPROP 1 LASTPIN (2350 2225) BN 0
J 0
(2338 2233);
DISPLAY 0.680851 (2338 2233);
PAINT GREEN (2338 2233);
FORCEPROP 2 LAST CDS_LIB standard
J 0
(2400 2225);
PAINT MONO (2400 2225);
DISPLAY INVISIBLE (2400 2225);
FORCEPROP 1 LAST BODY_TYPE PLUMBING
J 0
(2400 2275);
DISPLAY 0.872340 (2400 2275);
PAINT GREEN (2400 2275);
DISPLAY INVISIBLE (2400 2275);
FORCEPROP 1 LAST HDL_TAP TRUE
J 0
(2725 2100);
DISPLAY 0.872340 (2725 2100);
DISPLAY INVISIBLE (2725 2100);
FORCEPROP 1 LAST PATH I133
J 0
(2398 2225);
DISPLAY 0.872340 (2398 2225);
PAINT GREEN (2398 2225);
DISPLAY INVISIBLE (2398 2225);
FORCEADD TAP..1
(2400 2325);
FORCEPROP 3 LASTPIN (2350 2325) SIG_NAME M_H_CPU0_SB_DQS_DP<1>
J 0
(2360 2335);
DISPLAY 0.659574 (2360 2335);
PAINT MONO (2360 2335);
DISPLAY INVISIBLE (2360 2335);
FORCEPROP 1 LASTPIN (2350 2325) BN 1
J 0
(2338 2333);
DISPLAY 0.680851 (2338 2333);
PAINT GREEN (2338 2333);
FORCEPROP 2 LAST CDS_LIB standard
J 0
(2400 2325);
DISPLAY INVISIBLE (2400 2325);
FORCEPROP 1 LAST BODY_TYPE PLUMBING
J 0
(2400 2375);
DISPLAY 0.872340 (2400 2375);
PAINT GREEN (2400 2375);
DISPLAY INVISIBLE (2400 2375);
FORCEPROP 1 LAST HDL_TAP TRUE
J 0
(2725 2200);
DISPLAY 0.872340 (2725 2200);
DISPLAY INVISIBLE (2725 2200);
FORCEPROP 1 LAST PATH I134
J 0
(2398 2325);
DISPLAY 0.872340 (2398 2325);
PAINT GREEN (2398 2325);
DISPLAY INVISIBLE (2398 2325);
FORCEADD TAP..1
(2575 2275);
FORCEPROP 3 LASTPIN (2525 2275) SIG_NAME M_H_CPU0_SB_DQS_DN<1>
J 0
(2535 2285);
DISPLAY 0.659574 (2535 2285);
PAINT MONO (2535 2285);
DISPLAY INVISIBLE (2535 2285);
FORCEPROP 1 LASTPIN (2525 2275) BN 1
J 0
(2513 2283);
DISPLAY 0.680851 (2513 2283);
PAINT GREEN (2513 2283);
FORCEPROP 2 LAST CDS_LIB standard
J 0
(2575 2275);
DISPLAY INVISIBLE (2575 2275);
FORCEPROP 1 LAST BODY_TYPE PLUMBING
J 0
(2575 2325);
DISPLAY 0.872340 (2575 2325);
PAINT GREEN (2575 2325);
DISPLAY INVISIBLE (2575 2325);
FORCEPROP 1 LAST HDL_TAP TRUE
J 0
(2900 2150);
DISPLAY 0.872340 (2900 2150);
DISPLAY INVISIBLE (2900 2150);
FORCEPROP 1 LAST PATH I135
J 0
(2573 2275);
DISPLAY 0.872340 (2573 2275);
PAINT GREEN (2573 2275);
DISPLAY INVISIBLE (2573 2275);
FORCEADD TAP..1
(2575 2175);
FORCEPROP 3 LASTPIN (2525 2175) SIG_NAME M_H_CPU0_SB_DQS_DN<0>
J 0
(2535 2185);
DISPLAY 0.659574 (2535 2185);
PAINT MONO (2535 2185);
DISPLAY INVISIBLE (2535 2185);
FORCEPROP 1 LASTPIN (2525 2175) BN 0
J 0
(2513 2183);
DISPLAY 0.680851 (2513 2183);
PAINT GREEN (2513 2183);
FORCEPROP 2 LAST CDS_LIB standard
J 0
(2575 2175);
PAINT MONO (2575 2175);
DISPLAY INVISIBLE (2575 2175);
FORCEPROP 1 LAST BODY_TYPE PLUMBING
J 0
(2575 2225);
DISPLAY 0.872340 (2575 2225);
PAINT GREEN (2575 2225);
DISPLAY INVISIBLE (2575 2225);
FORCEPROP 1 LAST HDL_TAP TRUE
J 0
(2900 2050);
DISPLAY 0.872340 (2900 2050);
DISPLAY INVISIBLE (2900 2050);
FORCEPROP 1 LAST PATH I136
J 0
(2573 2175);
DISPLAY 0.872340 (2573 2175);
PAINT GREEN (2573 2175);
DISPLAY INVISIBLE (2573 2175);
FORCEADD TAP..1
(2575 2375);
FORCEPROP 3 LASTPIN (2525 2375) SIG_NAME M_H_CPU0_SB_DQS_DN<2>
J 0
(2535 2385);
DISPLAY 0.659574 (2535 2385);
PAINT MONO (2535 2385);
DISPLAY INVISIBLE (2535 2385);
FORCEPROP 1 LASTPIN (2525 2375) BN 2
J 0
(2513 2383);
DISPLAY 0.680851 (2513 2383);
PAINT GREEN (2513 2383);
FORCEPROP 2 LAST CDS_LIB standard
J 0
(2575 2375);
DISPLAY INVISIBLE (2575 2375);
FORCEPROP 1 LAST BODY_TYPE PLUMBING
J 0
(2575 2425);
DISPLAY 0.872340 (2575 2425);
PAINT GREEN (2575 2425);
DISPLAY INVISIBLE (2575 2425);
FORCEPROP 1 LAST HDL_TAP TRUE
J 0
(2900 2250);
DISPLAY 0.872340 (2900 2250);
DISPLAY INVISIBLE (2900 2250);
FORCEPROP 1 LAST PATH I137
J 0
(2573 2375);
DISPLAY 0.872340 (2573 2375);
PAINT GREEN (2573 2375);
DISPLAY INVISIBLE (2573 2375);
FORCEADD TAP..1
(2400 2425);
FORCEPROP 3 LASTPIN (2350 2425) SIG_NAME M_H_CPU0_SB_DQS_DP<2>
J 0
(2360 2435);
DISPLAY 0.659574 (2360 2435);
PAINT MONO (2360 2435);
DISPLAY INVISIBLE (2360 2435);
FORCEPROP 1 LASTPIN (2350 2425) BN 2
J 0
(2338 2433);
DISPLAY 0.680851 (2338 2433);
PAINT GREEN (2338 2433);
FORCEPROP 2 LAST CDS_LIB standard
J 0
(2400 2425);
DISPLAY INVISIBLE (2400 2425);
FORCEPROP 1 LAST BODY_TYPE PLUMBING
J 0
(2400 2475);
DISPLAY 0.872340 (2400 2475);
PAINT GREEN (2400 2475);
DISPLAY INVISIBLE (2400 2475);
FORCEPROP 1 LAST HDL_TAP TRUE
J 0
(2725 2300);
DISPLAY 0.872340 (2725 2300);
DISPLAY INVISIBLE (2725 2300);
FORCEPROP 1 LAST PATH I138
J 0
(2398 2425);
DISPLAY 0.872340 (2398 2425);
PAINT GREEN (2398 2425);
DISPLAY INVISIBLE (2398 2425);
FORCEADD TAP..1
(2400 2625);
FORCEPROP 3 LASTPIN (2350 2625) SIG_NAME M_H_CPU0_SB_DQS_DP<4>
J 0
(2360 2635);
DISPLAY 0.659574 (2360 2635);
PAINT MONO (2360 2635);
DISPLAY INVISIBLE (2360 2635);
FORCEPROP 1 LASTPIN (2350 2625) BN 4
J 0
(2338 2633);
DISPLAY 0.680851 (2338 2633);
PAINT GREEN (2338 2633);
FORCEPROP 2 LAST CDS_LIB standard
J 0
(2400 2625);
PAINT MONO (2400 2625);
DISPLAY INVISIBLE (2400 2625);
FORCEPROP 1 LAST BODY_TYPE PLUMBING
J 0
(2400 2675);
DISPLAY 0.872340 (2400 2675);
PAINT GREEN (2400 2675);
DISPLAY INVISIBLE (2400 2675);
FORCEPROP 1 LAST HDL_TAP TRUE
J 0
(2725 2500);
DISPLAY 0.872340 (2725 2500);
DISPLAY INVISIBLE (2725 2500);
FORCEPROP 1 LAST PATH I139
J 0
(2398 2625);
DISPLAY 0.872340 (2398 2625);
PAINT GREEN (2398 2625);
DISPLAY INVISIBLE (2398 2625);
FORCEADD OFFPAGE..3
R 2
(-2925 2800);
FORCEPROP 2 LAST $XR1 96 
J 0
(-3264 2800);
DISPLAY 0.638298 (-3264 2800);
PAINT MONO (-3264 2800);
FORCEPROP 2 LAST $XR0 27 
J 0
(-3174 2800);
DISPLAY 0.638298 (-3174 2800);
PAINT MONO (-3174 2800);
FORCEPROP 2 LAST CDS_LIB standard
J 0
(-2925 2800);
PAINT MONO (-2925 2800);
DISPLAY INVISIBLE (-2925 2800);
FORCEPROP 1 LAST OFFPAGE TRUE
J 2
(-3250 2675);
DISPLAY 0.872340 (-3250 2675);
DISPLAY INVISIBLE (-3250 2675);
FORCEPROP 1 LAST COMMENT_BODY TRUE
J 2
(-2875 2700);
DISPLAY 0.872340 (-2875 2700);
PAINT GREEN (-2875 2700);
DISPLAY INVISIBLE (-2875 2700);
FORCEPROP 2 LAST PATH I14
J 0
(-2875 2875);
DISPLAY 1.021277 (-2875 2875);
DISPLAY INVISIBLE (-2875 2875);
FORCEADD TAP..1
(2400 2525);
FORCEPROP 3 LASTPIN (2350 2525) SIG_NAME M_H_CPU0_SB_DQS_DP<3>
J 0
(2360 2535);
DISPLAY 0.659574 (2360 2535);
PAINT MONO (2360 2535);
DISPLAY INVISIBLE (2360 2535);
FORCEPROP 1 LASTPIN (2350 2525) BN 3
J 0
(2338 2533);
DISPLAY 0.680851 (2338 2533);
PAINT GREEN (2338 2533);
FORCEPROP 2 LAST CDS_LIB standard
J 0
(2400 2525);
PAINT MONO (2400 2525);
DISPLAY INVISIBLE (2400 2525);
FORCEPROP 1 LAST BODY_TYPE PLUMBING
J 0
(2400 2575);
DISPLAY 0.872340 (2400 2575);
PAINT GREEN (2400 2575);
DISPLAY INVISIBLE (2400 2575);
FORCEPROP 1 LAST HDL_TAP TRUE
J 0
(2725 2400);
DISPLAY 0.872340 (2725 2400);
DISPLAY INVISIBLE (2725 2400);
FORCEPROP 1 LAST PATH I140
J 0
(2398 2525);
DISPLAY 0.872340 (2398 2525);
PAINT GREEN (2398 2525);
DISPLAY INVISIBLE (2398 2525);
FORCEADD TAP..1
(2400 2825);
FORCEPROP 3 LASTPIN (2350 2825) SIG_NAME M_H_CPU0_SB_DQS_DP<6>
J 0
(2360 2835);
DISPLAY 0.659574 (2360 2835);
PAINT MONO (2360 2835);
DISPLAY INVISIBLE (2360 2835);
FORCEPROP 1 LASTPIN (2350 2825) BN 6
J 0
(2338 2833);
DISPLAY 0.680851 (2338 2833);
PAINT GREEN (2338 2833);
FORCEPROP 2 LAST CDS_LIB standard
J 0
(2400 2825);
DISPLAY INVISIBLE (2400 2825);
FORCEPROP 1 LAST BODY_TYPE PLUMBING
J 0
(2400 2875);
DISPLAY 0.872340 (2400 2875);
PAINT GREEN (2400 2875);
DISPLAY INVISIBLE (2400 2875);
FORCEPROP 1 LAST HDL_TAP TRUE
J 0
(2725 2700);
DISPLAY 0.872340 (2725 2700);
DISPLAY INVISIBLE (2725 2700);
FORCEPROP 1 LAST PATH I141
J 0
(2398 2825);
DISPLAY 0.872340 (2398 2825);
PAINT GREEN (2398 2825);
DISPLAY INVISIBLE (2398 2825);
FORCEADD TAP..1
(2400 2725);
FORCEPROP 3 LASTPIN (2350 2725) SIG_NAME M_H_CPU0_SB_DQS_DP<5>
J 0
(2360 2735);
DISPLAY 0.659574 (2360 2735);
PAINT MONO (2360 2735);
DISPLAY INVISIBLE (2360 2735);
FORCEPROP 1 LASTPIN (2350 2725) BN 5
J 0
(2338 2733);
DISPLAY 0.680851 (2338 2733);
PAINT GREEN (2338 2733);
FORCEPROP 2 LAST CDS_LIB standard
J 0
(2400 2725);
DISPLAY INVISIBLE (2400 2725);
FORCEPROP 1 LAST BODY_TYPE PLUMBING
J 0
(2400 2775);
DISPLAY 0.872340 (2400 2775);
PAINT GREEN (2400 2775);
DISPLAY INVISIBLE (2400 2775);
FORCEPROP 1 LAST HDL_TAP TRUE
J 0
(2725 2600);
DISPLAY 0.872340 (2725 2600);
DISPLAY INVISIBLE (2725 2600);
FORCEPROP 1 LAST PATH I142
J 0
(2398 2725);
DISPLAY 0.872340 (2398 2725);
PAINT GREEN (2398 2725);
DISPLAY INVISIBLE (2398 2725);
FORCEADD TAP..1
(2575 2575);
FORCEPROP 3 LASTPIN (2525 2575) SIG_NAME M_H_CPU0_SB_DQS_DN<4>
J 0
(2535 2585);
DISPLAY 0.659574 (2535 2585);
PAINT MONO (2535 2585);
DISPLAY INVISIBLE (2535 2585);
FORCEPROP 1 LASTPIN (2525 2575) BN 4
J 0
(2513 2583);
DISPLAY 0.680851 (2513 2583);
PAINT GREEN (2513 2583);
FORCEPROP 2 LAST CDS_LIB standard
J 0
(2575 2575);
PAINT MONO (2575 2575);
DISPLAY INVISIBLE (2575 2575);
FORCEPROP 1 LAST BODY_TYPE PLUMBING
J 0
(2575 2625);
DISPLAY 0.872340 (2575 2625);
PAINT GREEN (2575 2625);
DISPLAY INVISIBLE (2575 2625);
FORCEPROP 1 LAST HDL_TAP TRUE
J 0
(2900 2450);
DISPLAY 0.872340 (2900 2450);
DISPLAY INVISIBLE (2900 2450);
FORCEPROP 1 LAST PATH I143
J 0
(2573 2575);
DISPLAY 0.872340 (2573 2575);
PAINT GREEN (2573 2575);
DISPLAY INVISIBLE (2573 2575);
FORCEADD TAP..1
(2575 2475);
FORCEPROP 3 LASTPIN (2525 2475) SIG_NAME M_H_CPU0_SB_DQS_DN<3>
J 0
(2535 2485);
DISPLAY 0.659574 (2535 2485);
PAINT MONO (2535 2485);
DISPLAY INVISIBLE (2535 2485);
FORCEPROP 1 LASTPIN (2525 2475) BN 3
J 0
(2513 2483);
DISPLAY 0.680851 (2513 2483);
PAINT GREEN (2513 2483);
FORCEPROP 2 LAST CDS_LIB standard
J 0
(2575 2475);
PAINT MONO (2575 2475);
DISPLAY INVISIBLE (2575 2475);
FORCEPROP 1 LAST BODY_TYPE PLUMBING
J 0
(2575 2525);
DISPLAY 0.872340 (2575 2525);
PAINT GREEN (2575 2525);
DISPLAY INVISIBLE (2575 2525);
FORCEPROP 1 LAST HDL_TAP TRUE
J 0
(2900 2350);
DISPLAY 0.872340 (2900 2350);
DISPLAY INVISIBLE (2900 2350);
FORCEPROP 1 LAST PATH I144
J 0
(2573 2475);
DISPLAY 0.872340 (2573 2475);
PAINT GREEN (2573 2475);
DISPLAY INVISIBLE (2573 2475);
FORCEADD TAP..1
(2575 2675);
FORCEPROP 3 LASTPIN (2525 2675) SIG_NAME M_H_CPU0_SB_DQS_DN<5>
J 0
(2535 2685);
DISPLAY 0.659574 (2535 2685);
PAINT MONO (2535 2685);
DISPLAY INVISIBLE (2535 2685);
FORCEPROP 1 LASTPIN (2525 2675) BN 5
J 0
(2513 2683);
DISPLAY 0.680851 (2513 2683);
PAINT GREEN (2513 2683);
FORCEPROP 2 LAST CDS_LIB standard
J 0
(2575 2675);
DISPLAY INVISIBLE (2575 2675);
FORCEPROP 1 LAST BODY_TYPE PLUMBING
J 0
(2575 2725);
DISPLAY 0.872340 (2575 2725);
PAINT GREEN (2575 2725);
DISPLAY INVISIBLE (2575 2725);
FORCEPROP 1 LAST HDL_TAP TRUE
J 0
(2900 2550);
DISPLAY 0.872340 (2900 2550);
DISPLAY INVISIBLE (2900 2550);
FORCEPROP 1 LAST PATH I145
J 0
(2573 2675);
DISPLAY 0.872340 (2573 2675);
PAINT GREEN (2573 2675);
DISPLAY INVISIBLE (2573 2675);
FORCEADD TAP..1
(2575 2875);
FORCEPROP 3 LASTPIN (2525 2875) SIG_NAME M_H_CPU0_SB_DQS_DN<7>
J 0
(2535 2885);
DISPLAY 0.659574 (2535 2885);
PAINT MONO (2535 2885);
DISPLAY INVISIBLE (2535 2885);
FORCEPROP 1 LASTPIN (2525 2875) BN 7
J 0
(2513 2883);
DISPLAY 0.680851 (2513 2883);
PAINT GREEN (2513 2883);
FORCEPROP 2 LAST CDS_LIB standard
J 0
(2575 2875);
DISPLAY INVISIBLE (2575 2875);
FORCEPROP 1 LAST BODY_TYPE PLUMBING
J 0
(2575 2925);
DISPLAY 0.872340 (2575 2925);
PAINT GREEN (2575 2925);
DISPLAY INVISIBLE (2575 2925);
FORCEPROP 1 LAST HDL_TAP TRUE
J 0
(2900 2750);
DISPLAY 0.872340 (2900 2750);
DISPLAY INVISIBLE (2900 2750);
FORCEPROP 1 LAST PATH I146
J 0
(2573 2875);
DISPLAY 0.872340 (2573 2875);
PAINT GREEN (2573 2875);
DISPLAY INVISIBLE (2573 2875);
FORCEADD TAP..1
(2575 2775);
FORCEPROP 3 LASTPIN (2525 2775) SIG_NAME M_H_CPU0_SB_DQS_DN<6>
J 0
(2535 2785);
DISPLAY 0.659574 (2535 2785);
PAINT MONO (2535 2785);
DISPLAY INVISIBLE (2535 2785);
FORCEPROP 1 LASTPIN (2525 2775) BN 6
J 0
(2513 2783);
DISPLAY 0.680851 (2513 2783);
PAINT GREEN (2513 2783);
FORCEPROP 2 LAST CDS_LIB standard
J 0
(2575 2775);
DISPLAY INVISIBLE (2575 2775);
FORCEPROP 1 LAST BODY_TYPE PLUMBING
J 0
(2575 2825);
DISPLAY 0.872340 (2575 2825);
PAINT GREEN (2575 2825);
DISPLAY INVISIBLE (2575 2825);
FORCEPROP 1 LAST HDL_TAP TRUE
J 0
(2900 2650);
DISPLAY 0.872340 (2900 2650);
DISPLAY INVISIBLE (2900 2650);
FORCEPROP 1 LAST PATH I147
J 0
(2573 2775);
DISPLAY 0.872340 (2573 2775);
PAINT GREEN (2573 2775);
DISPLAY INVISIBLE (2573 2775);
FORCEADD TAP..1
(2400 2925);
FORCEPROP 3 LASTPIN (2350 2925) SIG_NAME M_H_CPU0_SB_DQS_DP<7>
J 0
(2360 2935);
DISPLAY 0.659574 (2360 2935);
PAINT MONO (2360 2935);
DISPLAY INVISIBLE (2360 2935);
FORCEPROP 1 LASTPIN (2350 2925) BN 7
J 0
(2338 2933);
DISPLAY 0.680851 (2338 2933);
PAINT GREEN (2338 2933);
FORCEPROP 2 LAST CDS_LIB standard
J 0
(2400 2925);
DISPLAY INVISIBLE (2400 2925);
FORCEPROP 1 LAST BODY_TYPE PLUMBING
J 0
(2400 2975);
DISPLAY 0.872340 (2400 2975);
PAINT GREEN (2400 2975);
DISPLAY INVISIBLE (2400 2975);
FORCEPROP 1 LAST HDL_TAP TRUE
J 0
(2725 2800);
DISPLAY 0.872340 (2725 2800);
DISPLAY INVISIBLE (2725 2800);
FORCEPROP 1 LAST PATH I148
J 0
(2398 2925);
DISPLAY 0.872340 (2398 2925);
PAINT GREEN (2398 2925);
DISPLAY INVISIBLE (2398 2925);
FORCEADD TAP..1
(2400 3025);
FORCEPROP 3 LASTPIN (2350 3025) SIG_NAME M_H_CPU0_SB_DQS_DP<8>
J 0
(2360 3035);
DISPLAY 0.659574 (2360 3035);
PAINT MONO (2360 3035);
DISPLAY INVISIBLE (2360 3035);
FORCEPROP 1 LASTPIN (2350 3025) BN 8
J 0
(2338 3033);
DISPLAY 0.680851 (2338 3033);
PAINT GREEN (2338 3033);
FORCEPROP 2 LAST CDS_LIB standard
J 0
(2400 3025);
DISPLAY INVISIBLE (2400 3025);
FORCEPROP 1 LAST BODY_TYPE PLUMBING
J 0
(2400 3075);
DISPLAY 0.872340 (2400 3075);
PAINT GREEN (2400 3075);
DISPLAY INVISIBLE (2400 3075);
FORCEPROP 1 LAST HDL_TAP TRUE
J 0
(2725 2900);
DISPLAY 0.872340 (2725 2900);
DISPLAY INVISIBLE (2725 2900);
FORCEPROP 1 LAST PATH I149
J 0
(2398 3025);
DISPLAY 0.872340 (2398 3025);
PAINT GREEN (2398 3025);
DISPLAY INVISIBLE (2398 3025);
FORCEADD OFFPAGE..1
(-2925 2900);
FORCEPROP 2 LAST $XR0 27 
J 0
(-3146 2900);
DISPLAY 0.638298 (-3146 2900);
PAINT MONO (-3146 2900);
FORCEPROP 2 LAST CDS_LIB standard
J 0
(-2925 2900);
PAINT MONO (-2925 2900);
DISPLAY INVISIBLE (-2925 2900);
FORCEPROP 1 LAST OFFPAGE TRUE
J 0
(-2600 2775);
DISPLAY 0.872340 (-2600 2775);
DISPLAY INVISIBLE (-2600 2775);
FORCEPROP 1 LAST COMMENT_BODY TRUE
J 0
(-2800 2800);
DISPLAY 0.872340 (-2800 2800);
PAINT GREEN (-2800 2800);
DISPLAY INVISIBLE (-2800 2800);
FORCEPROP 2 LAST PATH I15
J 0
(-2875 2975);
DISPLAY 1.021277 (-2875 2975);
DISPLAY INVISIBLE (-2875 2975);
FORCEADD TAP..1
(2400 3125);
FORCEPROP 3 LASTPIN (2350 3125) SIG_NAME M_H_CPU0_SB_DQS_DP<9>
J 0
(2360 3135);
DISPLAY 0.659574 (2360 3135);
PAINT MONO (2360 3135);
DISPLAY INVISIBLE (2360 3135);
FORCEPROP 1 LASTPIN (2350 3125) BN 9
J 0
(2338 3133);
DISPLAY 0.680851 (2338 3133);
PAINT GREEN (2338 3133);
FORCEPROP 2 LAST CDS_LIB standard
J 0
(2400 3125);
DISPLAY INVISIBLE (2400 3125);
FORCEPROP 1 LAST BODY_TYPE PLUMBING
J 0
(2400 3175);
DISPLAY 0.872340 (2400 3175);
PAINT GREEN (2400 3175);
DISPLAY INVISIBLE (2400 3175);
FORCEPROP 1 LAST HDL_TAP TRUE
J 0
(2725 3000);
DISPLAY 0.872340 (2725 3000);
DISPLAY INVISIBLE (2725 3000);
FORCEPROP 1 LAST PATH I150
J 0
(2398 3125);
DISPLAY 0.872340 (2398 3125);
PAINT GREEN (2398 3125);
DISPLAY INVISIBLE (2398 3125);
FORCEADD TAP..1
(2400 3375);
FORCEPROP 3 LASTPIN (2350 3375) SIG_NAME M_H_CPU0_SA_DQS_DP<1>
J 0
(2360 3385);
DISPLAY 0.659574 (2360 3385);
PAINT MONO (2360 3385);
DISPLAY INVISIBLE (2360 3385);
FORCEPROP 1 LASTPIN (2350 3375) BN 1
J 0
(2338 3383);
DISPLAY 0.680851 (2338 3383);
PAINT GREEN (2338 3383);
FORCEPROP 2 LAST CDS_LIB standard
J 0
(2400 3375);
DISPLAY INVISIBLE (2400 3375);
FORCEPROP 1 LAST BODY_TYPE PLUMBING
J 0
(2400 3425);
DISPLAY 0.872340 (2400 3425);
PAINT GREEN (2400 3425);
DISPLAY INVISIBLE (2400 3425);
FORCEPROP 1 LAST HDL_TAP TRUE
J 0
(2725 3250);
DISPLAY 0.872340 (2725 3250);
DISPLAY INVISIBLE (2725 3250);
FORCEPROP 1 LAST PATH I151
J 0
(2398 3375);
DISPLAY 0.872340 (2398 3375);
PAINT GREEN (2398 3375);
DISPLAY INVISIBLE (2398 3375);
FORCEADD TAP..1
(2400 3275);
FORCEPROP 3 LASTPIN (2350 3275) SIG_NAME M_H_CPU0_SA_DQS_DP<0>
J 0
(2360 3285);
DISPLAY 0.659574 (2360 3285);
PAINT MONO (2360 3285);
DISPLAY INVISIBLE (2360 3285);
FORCEPROP 1 LASTPIN (2350 3275) BN 0
J 0
(2338 3283);
DISPLAY 0.680851 (2338 3283);
PAINT GREEN (2338 3283);
FORCEPROP 2 LAST CDS_LIB standard
J 0
(2400 3275);
PAINT MONO (2400 3275);
DISPLAY INVISIBLE (2400 3275);
FORCEPROP 1 LAST BODY_TYPE PLUMBING
J 0
(2400 3325);
DISPLAY 0.872340 (2400 3325);
PAINT GREEN (2400 3325);
DISPLAY INVISIBLE (2400 3325);
FORCEPROP 1 LAST HDL_TAP TRUE
J 0
(2725 3150);
DISPLAY 0.872340 (2725 3150);
DISPLAY INVISIBLE (2725 3150);
FORCEPROP 1 LAST PATH I152
J 0
(2398 3275);
DISPLAY 0.872340 (2398 3275);
PAINT GREEN (2398 3275);
DISPLAY INVISIBLE (2398 3275);
FORCEADD TAP..1
(2575 2975);
FORCEPROP 3 LASTPIN (2525 2975) SIG_NAME M_H_CPU0_SB_DQS_DN<8>
J 0
(2535 2985);
DISPLAY 0.659574 (2535 2985);
PAINT MONO (2535 2985);
DISPLAY INVISIBLE (2535 2985);
FORCEPROP 1 LASTPIN (2525 2975) BN 8
J 0
(2513 2983);
DISPLAY 0.680851 (2513 2983);
PAINT GREEN (2513 2983);
FORCEPROP 2 LAST CDS_LIB standard
J 0
(2575 2975);
DISPLAY INVISIBLE (2575 2975);
FORCEPROP 1 LAST BODY_TYPE PLUMBING
J 0
(2575 3025);
DISPLAY 0.872340 (2575 3025);
PAINT GREEN (2575 3025);
DISPLAY INVISIBLE (2575 3025);
FORCEPROP 1 LAST HDL_TAP TRUE
J 0
(2900 2850);
DISPLAY 0.872340 (2900 2850);
DISPLAY INVISIBLE (2900 2850);
FORCEPROP 1 LAST PATH I153
J 0
(2573 2975);
DISPLAY 0.872340 (2573 2975);
PAINT GREEN (2573 2975);
DISPLAY INVISIBLE (2573 2975);
FORCEADD TAP..1
(2575 3075);
FORCEPROP 3 LASTPIN (2525 3075) SIG_NAME M_H_CPU0_SB_DQS_DN<9>
J 0
(2535 3085);
DISPLAY 0.659574 (2535 3085);
PAINT MONO (2535 3085);
DISPLAY INVISIBLE (2535 3085);
FORCEPROP 1 LASTPIN (2525 3075) BN 9
J 0
(2513 3083);
DISPLAY 0.680851 (2513 3083);
PAINT GREEN (2513 3083);
FORCEPROP 2 LAST CDS_LIB standard
J 0
(2575 3075);
DISPLAY INVISIBLE (2575 3075);
FORCEPROP 1 LAST BODY_TYPE PLUMBING
J 0
(2575 3125);
DISPLAY 0.872340 (2575 3125);
PAINT GREEN (2575 3125);
DISPLAY INVISIBLE (2575 3125);
FORCEPROP 1 LAST HDL_TAP TRUE
J 0
(2900 2950);
DISPLAY 0.872340 (2900 2950);
DISPLAY INVISIBLE (2900 2950);
FORCEPROP 1 LAST PATH I154
J 0
(2573 3075);
DISPLAY 0.872340 (2573 3075);
PAINT GREEN (2573 3075);
DISPLAY INVISIBLE (2573 3075);
FORCEADD TAP..1
(2575 3325);
FORCEPROP 3 LASTPIN (2525 3325) SIG_NAME M_H_CPU0_SA_DQS_DN<1>
J 0
(2535 3335);
DISPLAY 0.659574 (2535 3335);
PAINT MONO (2535 3335);
DISPLAY INVISIBLE (2535 3335);
FORCEPROP 1 LASTPIN (2525 3325) BN 1
J 0
(2513 3333);
DISPLAY 0.680851 (2513 3333);
PAINT GREEN (2513 3333);
FORCEPROP 2 LAST CDS_LIB standard
J 0
(2575 3325);
DISPLAY INVISIBLE (2575 3325);
FORCEPROP 1 LAST BODY_TYPE PLUMBING
J 0
(2575 3375);
DISPLAY 0.872340 (2575 3375);
PAINT GREEN (2575 3375);
DISPLAY INVISIBLE (2575 3375);
FORCEPROP 1 LAST HDL_TAP TRUE
J 0
(2900 3200);
DISPLAY 0.872340 (2900 3200);
DISPLAY INVISIBLE (2900 3200);
FORCEPROP 1 LAST PATH I155
J 0
(2573 3325);
DISPLAY 0.872340 (2573 3325);
PAINT GREEN (2573 3325);
DISPLAY INVISIBLE (2573 3325);
FORCEADD TAP..1
(2575 3225);
FORCEPROP 3 LASTPIN (2525 3225) SIG_NAME M_H_CPU0_SA_DQS_DN<0>
J 0
(2535 3235);
DISPLAY 0.659574 (2535 3235);
PAINT MONO (2535 3235);
DISPLAY INVISIBLE (2535 3235);
FORCEPROP 1 LASTPIN (2525 3225) BN 0
J 0
(2513 3233);
DISPLAY 0.680851 (2513 3233);
PAINT GREEN (2513 3233);
FORCEPROP 2 LAST CDS_LIB standard
J 0
(2575 3225);
PAINT MONO (2575 3225);
DISPLAY INVISIBLE (2575 3225);
FORCEPROP 1 LAST BODY_TYPE PLUMBING
J 0
(2575 3275);
DISPLAY 0.872340 (2575 3275);
PAINT GREEN (2575 3275);
DISPLAY INVISIBLE (2575 3275);
FORCEPROP 1 LAST HDL_TAP TRUE
J 0
(2900 3100);
DISPLAY 0.872340 (2900 3100);
DISPLAY INVISIBLE (2900 3100);
FORCEPROP 1 LAST PATH I156
J 0
(2573 3225);
DISPLAY 0.872340 (2573 3225);
PAINT GREEN (2573 3225);
DISPLAY INVISIBLE (2573 3225);
FORCEADD TAP..1
(2400 3475);
FORCEPROP 3 LASTPIN (2350 3475) SIG_NAME M_H_CPU0_SA_DQS_DP<2>
J 0
(2360 3485);
DISPLAY 0.659574 (2360 3485);
PAINT MONO (2360 3485);
DISPLAY INVISIBLE (2360 3485);
FORCEPROP 1 LASTPIN (2350 3475) BN 2
J 0
(2338 3483);
DISPLAY 0.680851 (2338 3483);
PAINT GREEN (2338 3483);
FORCEPROP 2 LAST CDS_LIB standard
J 0
(2400 3475);
DISPLAY INVISIBLE (2400 3475);
FORCEPROP 1 LAST BODY_TYPE PLUMBING
J 0
(2400 3525);
DISPLAY 0.872340 (2400 3525);
PAINT GREEN (2400 3525);
DISPLAY INVISIBLE (2400 3525);
FORCEPROP 1 LAST HDL_TAP TRUE
J 0
(2725 3350);
DISPLAY 0.872340 (2725 3350);
DISPLAY INVISIBLE (2725 3350);
FORCEPROP 1 LAST PATH I157
J 0
(2398 3475);
DISPLAY 0.872340 (2398 3475);
PAINT GREEN (2398 3475);
DISPLAY INVISIBLE (2398 3475);
FORCEADD TAP..1
(2400 3575);
FORCEPROP 3 LASTPIN (2350 3575) SIG_NAME M_H_CPU0_SA_DQS_DP<3>
J 0
(2360 3585);
DISPLAY 0.659574 (2360 3585);
PAINT MONO (2360 3585);
DISPLAY INVISIBLE (2360 3585);
FORCEPROP 1 LASTPIN (2350 3575) BN 3
J 0
(2338 3583);
DISPLAY 0.680851 (2338 3583);
PAINT GREEN (2338 3583);
FORCEPROP 2 LAST CDS_LIB standard
J 0
(2400 3575);
PAINT MONO (2400 3575);
DISPLAY INVISIBLE (2400 3575);
FORCEPROP 1 LAST BODY_TYPE PLUMBING
J 0
(2400 3625);
DISPLAY 0.872340 (2400 3625);
PAINT GREEN (2400 3625);
DISPLAY INVISIBLE (2400 3625);
FORCEPROP 1 LAST HDL_TAP TRUE
J 0
(2725 3450);
DISPLAY 0.872340 (2725 3450);
DISPLAY INVISIBLE (2725 3450);
FORCEPROP 1 LAST PATH I158
J 0
(2398 3575);
DISPLAY 0.872340 (2398 3575);
PAINT GREEN (2398 3575);
DISPLAY INVISIBLE (2398 3575);
FORCEADD TAP..1
(2400 3775);
FORCEPROP 3 LASTPIN (2350 3775) SIG_NAME M_H_CPU0_SA_DQS_DP<5>
J 0
(2360 3785);
DISPLAY 0.659574 (2360 3785);
PAINT MONO (2360 3785);
DISPLAY INVISIBLE (2360 3785);
FORCEPROP 1 LASTPIN (2350 3775) BN 5
J 0
(2338 3783);
DISPLAY 0.680851 (2338 3783);
PAINT GREEN (2338 3783);
FORCEPROP 2 LAST CDS_LIB standard
J 0
(2400 3775);
DISPLAY INVISIBLE (2400 3775);
FORCEPROP 1 LAST BODY_TYPE PLUMBING
J 0
(2400 3825);
DISPLAY 0.872340 (2400 3825);
PAINT GREEN (2400 3825);
DISPLAY INVISIBLE (2400 3825);
FORCEPROP 1 LAST HDL_TAP TRUE
J 0
(2725 3650);
DISPLAY 0.872340 (2725 3650);
DISPLAY INVISIBLE (2725 3650);
FORCEPROP 1 LAST PATH I159
J 0
(2398 3775);
DISPLAY 0.872340 (2398 3775);
PAINT GREEN (2398 3775);
DISPLAY INVISIBLE (2398 3775);
FORCEADD OFFPAGE..1
(-2925 2850);
FORCEPROP 2 LAST $XR0 27 
J 0
(-3146 2850);
DISPLAY 0.638298 (-3146 2850);
PAINT MONO (-3146 2850);
FORCEPROP 2 LAST CDS_LIB standard
J 0
(-2925 2850);
PAINT MONO (-2925 2850);
DISPLAY INVISIBLE (-2925 2850);
FORCEPROP 1 LAST OFFPAGE TRUE
J 0
(-2600 2725);
DISPLAY 0.872340 (-2600 2725);
DISPLAY INVISIBLE (-2600 2725);
FORCEPROP 1 LAST COMMENT_BODY TRUE
J 0
(-2800 2750);
DISPLAY 0.872340 (-2800 2750);
PAINT GREEN (-2800 2750);
DISPLAY INVISIBLE (-2800 2750);
FORCEPROP 2 LAST PATH I16
J 0
(-2875 2925);
DISPLAY 1.021277 (-2875 2925);
DISPLAY INVISIBLE (-2875 2925);
FORCEADD TAP..1
(2400 3675);
FORCEPROP 3 LASTPIN (2350 3675) SIG_NAME M_H_CPU0_SA_DQS_DP<4>
J 0
(2360 3685);
DISPLAY 0.659574 (2360 3685);
PAINT MONO (2360 3685);
DISPLAY INVISIBLE (2360 3685);
FORCEPROP 1 LASTPIN (2350 3675) BN 4
J 0
(2338 3683);
DISPLAY 0.680851 (2338 3683);
PAINT GREEN (2338 3683);
FORCEPROP 2 LAST CDS_LIB standard
J 0
(2400 3675);
PAINT MONO (2400 3675);
DISPLAY INVISIBLE (2400 3675);
FORCEPROP 1 LAST BODY_TYPE PLUMBING
J 0
(2400 3725);
DISPLAY 0.872340 (2400 3725);
PAINT GREEN (2400 3725);
DISPLAY INVISIBLE (2400 3725);
FORCEPROP 1 LAST HDL_TAP TRUE
J 0
(2725 3550);
DISPLAY 0.872340 (2725 3550);
DISPLAY INVISIBLE (2725 3550);
FORCEPROP 1 LAST PATH I160
J 0
(2398 3675);
DISPLAY 0.872340 (2398 3675);
PAINT GREEN (2398 3675);
DISPLAY INVISIBLE (2398 3675);
FORCEADD TAP..1
(2400 3875);
FORCEPROP 3 LASTPIN (2350 3875) SIG_NAME M_H_CPU0_SA_DQS_DP<6>
J 0
(2360 3885);
DISPLAY 0.659574 (2360 3885);
PAINT MONO (2360 3885);
DISPLAY INVISIBLE (2360 3885);
FORCEPROP 1 LASTPIN (2350 3875) BN 6
J 0
(2338 3883);
DISPLAY 0.680851 (2338 3883);
PAINT GREEN (2338 3883);
FORCEPROP 2 LAST CDS_LIB standard
J 0
(2400 3875);
DISPLAY INVISIBLE (2400 3875);
FORCEPROP 1 LAST BODY_TYPE PLUMBING
J 0
(2400 3925);
DISPLAY 0.872340 (2400 3925);
PAINT GREEN (2400 3925);
DISPLAY INVISIBLE (2400 3925);
FORCEPROP 1 LAST HDL_TAP TRUE
J 0
(2725 3750);
DISPLAY 0.872340 (2725 3750);
DISPLAY INVISIBLE (2725 3750);
FORCEPROP 1 LAST PATH I161
J 0
(2398 3875);
DISPLAY 0.872340 (2398 3875);
PAINT GREEN (2398 3875);
DISPLAY INVISIBLE (2398 3875);
FORCEADD TAP..1
(2575 3425);
FORCEPROP 3 LASTPIN (2525 3425) SIG_NAME M_H_CPU0_SA_DQS_DN<2>
J 0
(2535 3435);
DISPLAY 0.659574 (2535 3435);
PAINT MONO (2535 3435);
DISPLAY INVISIBLE (2535 3435);
FORCEPROP 1 LASTPIN (2525 3425) BN 2
J 0
(2513 3433);
DISPLAY 0.680851 (2513 3433);
PAINT GREEN (2513 3433);
FORCEPROP 2 LAST CDS_LIB standard
J 0
(2575 3425);
DISPLAY INVISIBLE (2575 3425);
FORCEPROP 1 LAST BODY_TYPE PLUMBING
J 0
(2575 3475);
DISPLAY 0.872340 (2575 3475);
PAINT GREEN (2575 3475);
DISPLAY INVISIBLE (2575 3475);
FORCEPROP 1 LAST HDL_TAP TRUE
J 0
(2900 3300);
DISPLAY 0.872340 (2900 3300);
DISPLAY INVISIBLE (2900 3300);
FORCEPROP 1 LAST PATH I162
J 0
(2573 3425);
DISPLAY 0.872340 (2573 3425);
PAINT GREEN (2573 3425);
DISPLAY INVISIBLE (2573 3425);
FORCEADD TAP..1
(2575 3525);
FORCEPROP 3 LASTPIN (2525 3525) SIG_NAME M_H_CPU0_SA_DQS_DN<3>
J 0
(2535 3535);
DISPLAY 0.659574 (2535 3535);
PAINT MONO (2535 3535);
DISPLAY INVISIBLE (2535 3535);
FORCEPROP 1 LASTPIN (2525 3525) BN 3
J 0
(2513 3533);
DISPLAY 0.680851 (2513 3533);
PAINT GREEN (2513 3533);
FORCEPROP 2 LAST CDS_LIB standard
J 0
(2575 3525);
PAINT MONO (2575 3525);
DISPLAY INVISIBLE (2575 3525);
FORCEPROP 1 LAST BODY_TYPE PLUMBING
J 0
(2575 3575);
DISPLAY 0.872340 (2575 3575);
PAINT GREEN (2575 3575);
DISPLAY INVISIBLE (2575 3575);
FORCEPROP 1 LAST HDL_TAP TRUE
J 0
(2900 3400);
DISPLAY 0.872340 (2900 3400);
DISPLAY INVISIBLE (2900 3400);
FORCEPROP 1 LAST PATH I163
J 0
(2573 3525);
DISPLAY 0.872340 (2573 3525);
PAINT GREEN (2573 3525);
DISPLAY INVISIBLE (2573 3525);
FORCEADD TAP..1
(2575 3625);
FORCEPROP 3 LASTPIN (2525 3625) SIG_NAME M_H_CPU0_SA_DQS_DN<4>
J 0
(2535 3635);
DISPLAY 0.659574 (2535 3635);
PAINT MONO (2535 3635);
DISPLAY INVISIBLE (2535 3635);
FORCEPROP 1 LASTPIN (2525 3625) BN 4
J 0
(2513 3633);
DISPLAY 0.680851 (2513 3633);
PAINT GREEN (2513 3633);
FORCEPROP 2 LAST CDS_LIB standard
J 0
(2575 3625);
PAINT MONO (2575 3625);
DISPLAY INVISIBLE (2575 3625);
FORCEPROP 1 LAST BODY_TYPE PLUMBING
J 0
(2575 3675);
DISPLAY 0.872340 (2575 3675);
PAINT GREEN (2575 3675);
DISPLAY INVISIBLE (2575 3675);
FORCEPROP 1 LAST HDL_TAP TRUE
J 0
(2900 3500);
DISPLAY 0.872340 (2900 3500);
DISPLAY INVISIBLE (2900 3500);
FORCEPROP 1 LAST PATH I164
J 0
(2573 3625);
DISPLAY 0.872340 (2573 3625);
PAINT GREEN (2573 3625);
DISPLAY INVISIBLE (2573 3625);
FORCEADD TAP..1
(2575 3725);
FORCEPROP 3 LASTPIN (2525 3725) SIG_NAME M_H_CPU0_SA_DQS_DN<5>
J 0
(2535 3735);
DISPLAY 0.659574 (2535 3735);
PAINT MONO (2535 3735);
DISPLAY INVISIBLE (2535 3735);
FORCEPROP 1 LASTPIN (2525 3725) BN 5
J 0
(2513 3733);
DISPLAY 0.680851 (2513 3733);
PAINT GREEN (2513 3733);
FORCEPROP 2 LAST CDS_LIB standard
J 0
(2575 3725);
DISPLAY INVISIBLE (2575 3725);
FORCEPROP 1 LAST BODY_TYPE PLUMBING
J 0
(2575 3775);
DISPLAY 0.872340 (2575 3775);
PAINT GREEN (2575 3775);
DISPLAY INVISIBLE (2575 3775);
FORCEPROP 1 LAST HDL_TAP TRUE
J 0
(2900 3600);
DISPLAY 0.872340 (2900 3600);
DISPLAY INVISIBLE (2900 3600);
FORCEPROP 1 LAST PATH I165
J 0
(2573 3725);
DISPLAY 0.872340 (2573 3725);
PAINT GREEN (2573 3725);
DISPLAY INVISIBLE (2573 3725);
FORCEADD TAP..1
(2575 3825);
FORCEPROP 3 LASTPIN (2525 3825) SIG_NAME M_H_CPU0_SA_DQS_DN<6>
J 0
(2535 3835);
DISPLAY 0.659574 (2535 3835);
PAINT MONO (2535 3835);
DISPLAY INVISIBLE (2535 3835);
FORCEPROP 1 LASTPIN (2525 3825) BN 6
J 0
(2513 3833);
DISPLAY 0.680851 (2513 3833);
PAINT GREEN (2513 3833);
FORCEPROP 2 LAST CDS_LIB standard
J 0
(2575 3825);
DISPLAY INVISIBLE (2575 3825);
FORCEPROP 1 LAST BODY_TYPE PLUMBING
J 0
(2575 3875);
DISPLAY 0.872340 (2575 3875);
PAINT GREEN (2575 3875);
DISPLAY INVISIBLE (2575 3875);
FORCEPROP 1 LAST HDL_TAP TRUE
J 0
(2900 3700);
DISPLAY 0.872340 (2900 3700);
DISPLAY INVISIBLE (2900 3700);
FORCEPROP 1 LAST PATH I166
J 0
(2573 3825);
DISPLAY 0.872340 (2573 3825);
PAINT GREEN (2573 3825);
DISPLAY INVISIBLE (2573 3825);
FORCEADD TAP..1
(2400 3975);
FORCEPROP 3 LASTPIN (2350 3975) SIG_NAME M_H_CPU0_SA_DQS_DP<7>
J 0
(2360 3985);
DISPLAY 0.659574 (2360 3985);
PAINT MONO (2360 3985);
DISPLAY INVISIBLE (2360 3985);
FORCEPROP 1 LASTPIN (2350 3975) BN 7
J 0
(2338 3983);
DISPLAY 0.680851 (2338 3983);
PAINT GREEN (2338 3983);
FORCEPROP 2 LAST CDS_LIB standard
J 0
(2400 3975);
DISPLAY INVISIBLE (2400 3975);
FORCEPROP 1 LAST BODY_TYPE PLUMBING
J 0
(2400 4025);
DISPLAY 0.872340 (2400 4025);
PAINT GREEN (2400 4025);
DISPLAY INVISIBLE (2400 4025);
FORCEPROP 1 LAST HDL_TAP TRUE
J 0
(2725 3850);
DISPLAY 0.872340 (2725 3850);
DISPLAY INVISIBLE (2725 3850);
FORCEPROP 1 LAST PATH I167
J 0
(2398 3975);
DISPLAY 0.872340 (2398 3975);
PAINT GREEN (2398 3975);
DISPLAY INVISIBLE (2398 3975);
FORCEADD TAP..1
(2400 4175);
FORCEPROP 3 LASTPIN (2350 4175) SIG_NAME M_H_CPU0_SA_DQS_DP<9>
J 0
(2360 4185);
DISPLAY 0.659574 (2360 4185);
PAINT MONO (2360 4185);
DISPLAY INVISIBLE (2360 4185);
FORCEPROP 1 LASTPIN (2350 4175) BN 9
J 0
(2338 4183);
DISPLAY 0.680851 (2338 4183);
PAINT GREEN (2338 4183);
FORCEPROP 2 LAST CDS_LIB standard
J 0
(2400 4175);
DISPLAY INVISIBLE (2400 4175);
FORCEPROP 1 LAST BODY_TYPE PLUMBING
J 0
(2400 4225);
DISPLAY 0.872340 (2400 4225);
PAINT GREEN (2400 4225);
DISPLAY INVISIBLE (2400 4225);
FORCEPROP 1 LAST HDL_TAP TRUE
J 0
(2725 4050);
DISPLAY 0.872340 (2725 4050);
DISPLAY INVISIBLE (2725 4050);
FORCEPROP 1 LAST PATH I168
J 0
(2398 4175);
DISPLAY 0.872340 (2398 4175);
PAINT GREEN (2398 4175);
DISPLAY INVISIBLE (2398 4175);
FORCEADD TAP..1
(2400 4075);
FORCEPROP 3 LASTPIN (2350 4075) SIG_NAME M_H_CPU0_SA_DQS_DP<8>
J 0
(2360 4085);
DISPLAY 0.659574 (2360 4085);
PAINT MONO (2360 4085);
DISPLAY INVISIBLE (2360 4085);
FORCEPROP 1 LASTPIN (2350 4075) BN 8
J 0
(2338 4083);
DISPLAY 0.680851 (2338 4083);
PAINT GREEN (2338 4083);
FORCEPROP 2 LAST CDS_LIB standard
J 0
(2400 4075);
DISPLAY INVISIBLE (2400 4075);
FORCEPROP 1 LAST BODY_TYPE PLUMBING
J 0
(2400 4125);
DISPLAY 0.872340 (2400 4125);
PAINT GREEN (2400 4125);
DISPLAY INVISIBLE (2400 4125);
FORCEPROP 1 LAST HDL_TAP TRUE
J 0
(2725 3950);
DISPLAY 0.872340 (2725 3950);
DISPLAY INVISIBLE (2725 3950);
FORCEPROP 1 LAST PATH I169
J 0
(2398 4075);
DISPLAY 0.872340 (2398 4075);
PAINT GREEN (2398 4075);
DISPLAY INVISIBLE (2398 4075);
FORCEADD OFFPAGE..1
(-2925 3000);
FORCEPROP 2 LAST $XR0 27 
J 0
(-3146 3000);
DISPLAY 0.638298 (-3146 3000);
PAINT MONO (-3146 3000);
FORCEPROP 2 LAST CDS_LIB standard
J 0
(-2925 3000);
PAINT MONO (-2925 3000);
DISPLAY INVISIBLE (-2925 3000);
FORCEPROP 1 LAST OFFPAGE TRUE
J 0
(-2600 2875);
DISPLAY 0.872340 (-2600 2875);
DISPLAY INVISIBLE (-2600 2875);
FORCEPROP 1 LAST COMMENT_BODY TRUE
J 0
(-2800 2900);
DISPLAY 0.872340 (-2800 2900);
PAINT GREEN (-2800 2900);
DISPLAY INVISIBLE (-2800 2900);
FORCEPROP 2 LAST PATH I17
J 0
(-2875 3075);
DISPLAY 1.021277 (-2875 3075);
DISPLAY INVISIBLE (-2875 3075);
FORCEADD TAP..1
(2575 4025);
FORCEPROP 3 LASTPIN (2525 4025) SIG_NAME M_H_CPU0_SA_DQS_DN<8>
J 0
(2535 4035);
DISPLAY 0.659574 (2535 4035);
PAINT MONO (2535 4035);
DISPLAY INVISIBLE (2535 4035);
FORCEPROP 1 LASTPIN (2525 4025) BN 8
J 0
(2513 4033);
DISPLAY 0.680851 (2513 4033);
PAINT GREEN (2513 4033);
FORCEPROP 2 LAST CDS_LIB standard
J 0
(2575 4025);
DISPLAY INVISIBLE (2575 4025);
FORCEPROP 1 LAST BODY_TYPE PLUMBING
J 0
(2575 4075);
DISPLAY 0.872340 (2575 4075);
PAINT GREEN (2575 4075);
DISPLAY INVISIBLE (2575 4075);
FORCEPROP 1 LAST HDL_TAP TRUE
J 0
(2900 3900);
DISPLAY 0.872340 (2900 3900);
DISPLAY INVISIBLE (2900 3900);
FORCEPROP 1 LAST PATH I170
J 0
(2573 4025);
DISPLAY 0.872340 (2573 4025);
PAINT GREEN (2573 4025);
DISPLAY INVISIBLE (2573 4025);
FORCEADD TAP..1
(2575 3925);
FORCEPROP 3 LASTPIN (2525 3925) SIG_NAME M_H_CPU0_SA_DQS_DN<7>
J 0
(2535 3935);
DISPLAY 0.659574 (2535 3935);
PAINT MONO (2535 3935);
DISPLAY INVISIBLE (2535 3935);
FORCEPROP 1 LASTPIN (2525 3925) BN 7
J 0
(2513 3933);
DISPLAY 0.680851 (2513 3933);
PAINT GREEN (2513 3933);
FORCEPROP 2 LAST CDS_LIB standard
J 0
(2575 3925);
DISPLAY INVISIBLE (2575 3925);
FORCEPROP 1 LAST BODY_TYPE PLUMBING
J 0
(2575 3975);
DISPLAY 0.872340 (2575 3975);
PAINT GREEN (2575 3975);
DISPLAY INVISIBLE (2575 3975);
FORCEPROP 1 LAST HDL_TAP TRUE
J 0
(2900 3800);
DISPLAY 0.872340 (2900 3800);
DISPLAY INVISIBLE (2900 3800);
FORCEPROP 1 LAST PATH I171
J 0
(2573 3925);
DISPLAY 0.872340 (2573 3925);
PAINT GREEN (2573 3925);
DISPLAY INVISIBLE (2573 3925);
FORCEADD TAP..1
(2575 4125);
FORCEPROP 3 LASTPIN (2525 4125) SIG_NAME M_H_CPU0_SA_DQS_DN<9>
J 0
(2535 4135);
DISPLAY 0.659574 (2535 4135);
PAINT MONO (2535 4135);
DISPLAY INVISIBLE (2535 4135);
FORCEPROP 1 LASTPIN (2525 4125) BN 9
J 0
(2513 4133);
DISPLAY 0.680851 (2513 4133);
PAINT GREEN (2513 4133);
FORCEPROP 2 LAST CDS_LIB standard
J 0
(2575 4125);
DISPLAY INVISIBLE (2575 4125);
FORCEPROP 1 LAST BODY_TYPE PLUMBING
J 0
(2575 4175);
DISPLAY 0.872340 (2575 4175);
PAINT GREEN (2575 4175);
DISPLAY INVISIBLE (2575 4175);
FORCEPROP 1 LAST HDL_TAP TRUE
J 0
(2900 4000);
DISPLAY 0.872340 (2900 4000);
DISPLAY INVISIBLE (2900 4000);
FORCEPROP 1 LAST PATH I172
J 0
(2573 4125);
DISPLAY 0.872340 (2573 4125);
PAINT GREEN (2573 4125);
DISPLAY INVISIBLE (2573 4125);
FORCEADD OFFPAGE..2
(3525 3100);
FORCEPROP 2 LAST $XR1 96 
J 0
(3804 3100);
DISPLAY 0.638298 (3804 3100);
PAINT MONO (3804 3100);
FORCEPROP 2 LAST $XR0 27 
J 0
(3714 3100);
DISPLAY 0.638298 (3714 3100);
PAINT MONO (3714 3100);
FORCEPROP 2 LAST CDS_LIB standard
J 0
(3525 3100);
PAINT MONO (3525 3100);
DISPLAY INVISIBLE (3525 3100);
FORCEPROP 1 LAST OFFPAGE TRUE
J 0
(3850 2975);
DISPLAY 1.170213 (3850 2975);
PAINT GREEN (3850 2975);
DISPLAY INVISIBLE (3850 2975);
FORCEPROP 1 LAST COMMENT_BODY TRUE
J 0
(3480 3005);
DISPLAY 1.170213 (3480 3005);
PAINT GREEN (3480 3005);
DISPLAY INVISIBLE (3480 3005);
FORCEPROP 2 LAST PATH I173
J 0
(3700 3175);
DISPLAY 1.021277 (3700 3175);
DISPLAY INVISIBLE (3700 3175);
FORCEADD OFFPAGE..2
(3525 3150);
FORCEPROP 2 LAST $XR1 96 
J 0
(3804 3150);
DISPLAY 0.638298 (3804 3150);
PAINT MONO (3804 3150);
FORCEPROP 2 LAST $XR0 27 
J 0
(3714 3150);
DISPLAY 0.638298 (3714 3150);
PAINT MONO (3714 3150);
FORCEPROP 2 LAST CDS_LIB standard
J 0
(3525 3150);
PAINT MONO (3525 3150);
DISPLAY INVISIBLE (3525 3150);
FORCEPROP 1 LAST OFFPAGE TRUE
J 0
(3850 3025);
DISPLAY 1.170213 (3850 3025);
PAINT GREEN (3850 3025);
DISPLAY INVISIBLE (3850 3025);
FORCEPROP 1 LAST COMMENT_BODY TRUE
J 0
(3480 3055);
DISPLAY 1.170213 (3480 3055);
PAINT GREEN (3480 3055);
DISPLAY INVISIBLE (3480 3055);
FORCEPROP 2 LAST PATH I174
J 0
(3700 3225);
DISPLAY 1.021277 (3700 3225);
DISPLAY INVISIBLE (3700 3225);
FORCEADD OFFPAGE..2
(3525 4150);
FORCEPROP 2 LAST $XR1 96 
J 0
(3804 4150);
DISPLAY 0.638298 (3804 4150);
PAINT MONO (3804 4150);
FORCEPROP 2 LAST $XR0 27 
J 0
(3714 4150);
DISPLAY 0.638298 (3714 4150);
PAINT MONO (3714 4150);
FORCEPROP 2 LAST CDS_LIB standard
J 0
(3525 4150);
PAINT MONO (3525 4150);
DISPLAY INVISIBLE (3525 4150);
FORCEPROP 1 LAST OFFPAGE TRUE
J 0
(3850 4025);
DISPLAY 1.170213 (3850 4025);
PAINT GREEN (3850 4025);
DISPLAY INVISIBLE (3850 4025);
FORCEPROP 1 LAST COMMENT_BODY TRUE
J 0
(3480 4055);
DISPLAY 1.170213 (3480 4055);
PAINT GREEN (3480 4055);
DISPLAY INVISIBLE (3480 4055);
FORCEPROP 2 LAST PATH I175
J 0
(3700 4225);
DISPLAY 1.021277 (3700 4225);
DISPLAY INVISIBLE (3700 4225);
FORCEADD OFFPAGE..2
(3525 4200);
FORCEPROP 2 LAST $XR1 96 
J 0
(3804 4200);
DISPLAY 0.638298 (3804 4200);
PAINT MONO (3804 4200);
FORCEPROP 2 LAST $XR0 27 
J 0
(3714 4200);
DISPLAY 0.638298 (3714 4200);
PAINT MONO (3714 4200);
FORCEPROP 2 LAST CDS_LIB standard
J 0
(3525 4200);
PAINT MONO (3525 4200);
DISPLAY INVISIBLE (3525 4200);
FORCEPROP 1 LAST OFFPAGE TRUE
J 0
(3850 4075);
DISPLAY 1.170213 (3850 4075);
PAINT GREEN (3850 4075);
DISPLAY INVISIBLE (3850 4075);
FORCEPROP 1 LAST COMMENT_BODY TRUE
J 0
(3480 4105);
DISPLAY 1.170213 (3480 4105);
PAINT GREEN (3480 4105);
DISPLAY INVISIBLE (3480 4105);
FORCEPROP 2 LAST PATH I176
J 0
(3700 4275);
DISPLAY 1.021277 (3700 4275);
DISPLAY INVISIBLE (3700 4275);
FORCEADD VCC_CORE..1
(4075 4725);
FORCEPROP 3 LASTPIN (4075 4675) SIG_NAME P12V_S3_AUX_CPU0_NVDIMM\g
J 0
(4085 4685);
DISPLAY 0.659574 (4085 4685);
PAINT MONO (4085 4685);
DISPLAY INVISIBLE (4085 4685);
FORCEPROP 1 LAST HDL_POWER P12V_S3_AUX_CPU0_NVDIMM
J 1
(4075 4775);
DISPLAY 1.148936 (4075 4775);
PAINT GREEN (4075 4775);
FORCEPROP 2 LAST CDS_LIB logical_power
J 0
(4075 4725);
PAINT MONO (4075 4725);
DISPLAY INVISIBLE (4075 4725);
FORCEPROP 1 LAST PATH I177
J 0
(4125 4750);
DISPLAY 0.872340 (4125 4750);
PAINT AQUA (4125 4750);
DISPLAY INVISIBLE (4125 4750);
FORCEADD SCONN288_ADR50017P087CC..2
(1475 3175);
FORCEPROP 1 LAST PART_NUMBER DFHST8FS460
J 0
(870 4463);
DISPLAY 0.723404 (870 4463);
PAINT GREEN (870 4463);
DISPLAY INVISIBLE (870 4463);
FORCEPROP 2 LAST PART_TYPE SMLF
J 0
(875 4700);
DISPLAY 1.021277 (875 4700);
FORCEPROP 1 LAST MATERIAL IO
J 0
(870 4336);
DISPLAY 0.723404 (870 4336);
PAINT GREEN (870 4336);
FORCEPROP 2 LAST VALUE SCONN288_ADR50017-P087CC
J 0
(875 4650);
DISPLAY 1.021277 (875 4650);
FORCEPROP 1 LAST LOCATION J16
J 0
(870 4610);
DISPLAY 0.723404 (870 4610);
PAINT GREEN (870 4610);
FORCEPROP 0 LASTPIN (2225 3225) $PN 12
J 0
(2235 3235);
DISPLAY 0.680851 (2235 3235);
PAINT MONO (2235 3235);
FORCEPROP 0 LASTPIN (2225 3275) $PN 11
J 0
(2235 3285);
DISPLAY 0.680851 (2235 3285);
PAINT MONO (2235 3285);
FORCEPROP 0 LASTPIN (2225 2175) $PN 105
J 0
(2235 2185);
DISPLAY 0.680851 (2235 2185);
PAINT MONO (2235 2185);
FORCEPROP 0 LASTPIN (2225 2225) $PN 104
J 0
(2235 2235);
DISPLAY 0.680851 (2235 2235);
PAINT MONO (2235 2235);
FORCEPROP 0 LASTPIN (2225 3325) $PN 23
J 0
(2235 3335);
DISPLAY 0.680851 (2235 3335);
PAINT MONO (2235 3335);
FORCEPROP 0 LASTPIN (2225 3375) $PN 22
J 0
(2235 3385);
DISPLAY 0.680851 (2235 3385);
PAINT MONO (2235 3385);
FORCEPROP 0 LASTPIN (2225 2275) $PN 116
J 0
(2235 2285);
DISPLAY 0.680851 (2235 2285);
PAINT MONO (2235 2285);
FORCEPROP 0 LASTPIN (2225 2325) $PN 115
J 0
(2235 2335);
DISPLAY 0.680851 (2235 2335);
PAINT MONO (2235 2335);
FORCEPROP 0 LASTPIN (2225 3425) $PN 34
J 0
(2235 3435);
DISPLAY 0.680851 (2235 3435);
PAINT MONO (2235 3435);
FORCEPROP 0 LASTPIN (2225 3475) $PN 33
J 0
(2235 3485);
DISPLAY 0.680851 (2235 3485);
PAINT MONO (2235 3485);
FORCEPROP 0 LASTPIN (2225 2375) $PN 127
J 0
(2235 2385);
DISPLAY 0.680851 (2235 2385);
PAINT MONO (2235 2385);
FORCEPROP 0 LASTPIN (2225 2425) $PN 126
J 0
(2235 2435);
DISPLAY 0.680851 (2235 2435);
PAINT MONO (2235 2435);
FORCEPROP 0 LASTPIN (2225 3525) $PN 45
J 0
(2235 3535);
DISPLAY 0.680851 (2235 3535);
PAINT MONO (2235 3535);
FORCEPROP 0 LASTPIN (2225 3575) $PN 44
J 0
(2235 3585);
DISPLAY 0.680851 (2235 3585);
PAINT MONO (2235 3585);
FORCEPROP 0 LASTPIN (2225 2475) $PN 138
J 0
(2235 2485);
DISPLAY 0.680851 (2235 2485);
PAINT MONO (2235 2485);
FORCEPROP 0 LASTPIN (2225 2525) $PN 137
J 0
(2235 2535);
DISPLAY 0.680851 (2235 2535);
PAINT MONO (2235 2535);
FORCEPROP 0 LASTPIN (2225 3625) $PN 56
J 0
(2235 3635);
DISPLAY 0.680851 (2235 3635);
PAINT MONO (2235 3635);
FORCEPROP 0 LASTPIN (2225 3675) $PN 55
J 0
(2235 3685);
DISPLAY 0.680851 (2235 3685);
PAINT MONO (2235 3685);
FORCEPROP 0 LASTPIN (2225 2575) $PN 238
J 0
(2235 2585);
DISPLAY 0.680851 (2235 2585);
PAINT MONO (2235 2585);
FORCEPROP 0 LASTPIN (2225 2625) $PN 239
J 0
(2235 2635);
DISPLAY 0.680851 (2235 2635);
PAINT MONO (2235 2635);
FORCEPROP 0 LASTPIN (2225 3725) $PN 156
J 0
(2235 3735);
DISPLAY 0.680851 (2235 3735);
PAINT MONO (2235 3735);
FORCEPROP 0 LASTPIN (2225 3775) $PN 157
J 0
(2235 3785);
DISPLAY 0.680851 (2235 3785);
PAINT MONO (2235 3785);
FORCEPROP 0 LASTPIN (2225 2675) $PN 249
J 0
(2235 2685);
DISPLAY 0.680851 (2235 2685);
PAINT MONO (2235 2685);
FORCEPROP 0 LASTPIN (2225 2725) $PN 250
J 0
(2235 2735);
DISPLAY 0.680851 (2235 2735);
PAINT MONO (2235 2735);
FORCEPROP 0 LASTPIN (2225 3825) $PN 167
J 0
(2235 3835);
DISPLAY 0.680851 (2235 3835);
PAINT MONO (2235 3835);
FORCEPROP 0 LASTPIN (2225 3875) $PN 168
J 0
(2235 3885);
DISPLAY 0.680851 (2235 3885);
PAINT MONO (2235 3885);
FORCEPROP 0 LASTPIN (2225 2775) $PN 260
J 0
(2235 2785);
DISPLAY 0.680851 (2235 2785);
PAINT MONO (2235 2785);
FORCEPROP 0 LASTPIN (2225 2825) $PN 261
J 0
(2235 2835);
DISPLAY 0.680851 (2235 2835);
PAINT MONO (2235 2835);
FORCEPROP 0 LASTPIN (2225 3925) $PN 178
J 0
(2235 3935);
DISPLAY 0.680851 (2235 3935);
PAINT MONO (2235 3935);
FORCEPROP 0 LASTPIN (2225 3975) $PN 179
J 0
(2235 3985);
DISPLAY 0.680851 (2235 3985);
PAINT MONO (2235 3985);
FORCEPROP 0 LASTPIN (2225 2875) $PN 271
J 0
(2235 2885);
DISPLAY 0.680851 (2235 2885);
PAINT MONO (2235 2885);
FORCEPROP 0 LASTPIN (2225 2925) $PN 272
J 0
(2235 2935);
DISPLAY 0.680851 (2235 2935);
PAINT MONO (2235 2935);
FORCEPROP 0 LASTPIN (2225 4025) $PN 189
J 0
(2235 4035);
DISPLAY 0.680851 (2235 4035);
PAINT MONO (2235 4035);
FORCEPROP 0 LASTPIN (2225 4075) $PN 190
J 0
(2235 4085);
DISPLAY 0.680851 (2235 4085);
PAINT MONO (2235 4085);
FORCEPROP 0 LASTPIN (2225 2975) $PN 282
J 0
(2235 2985);
DISPLAY 0.680851 (2235 2985);
PAINT MONO (2235 2985);
FORCEPROP 0 LASTPIN (2225 3025) $PN 283
J 0
(2235 3035);
DISPLAY 0.680851 (2235 3035);
PAINT MONO (2235 3035);
FORCEPROP 0 LASTPIN (2225 4125) $PN 200
J 0
(2235 4135);
DISPLAY 0.680851 (2235 4135);
PAINT MONO (2235 4135);
FORCEPROP 0 LASTPIN (2225 4175) $PN 201
J 0
(2235 4185);
DISPLAY 0.680851 (2235 4185);
PAINT MONO (2235 4185);
FORCEPROP 0 LASTPIN (2225 3075) $PN 94
J 0
(2235 3085);
DISPLAY 0.680851 (2235 3085);
PAINT MONO (2235 3085);
FORCEPROP 0 LASTPIN (2225 3125) $PN 93
J 0
(2235 3135);
DISPLAY 0.680851 (2235 3135);
PAINT MONO (2235 3135);
FORCEPROP 1 LAST NEEDS_NO_SIZE TRUE
J 0
(1475 3175);
DISPLAY 0.723404 (1475 3175);
PAINT GREEN (1475 3175);
DISPLAY INVISIBLE (1475 3175);
FORCEPROP 1 LAST CDS_LMAN_SYM_OUTLINE -600,1150,600,-1150
J 0
(1475 3175);
DISPLAY 0.468085 (1475 3175);
PAINT GREEN (1475 3175);
DISPLAY INVISIBLE (1475 3175);
FORCEPROP 2 LAST CDS_LIB pure_quanta
J 0
(1475 3175);
DISPLAY INVISIBLE (1475 3175);
FORCEPROP 0 LAST $SEC 2
J 0
(875 4750);
DISPLAY 0.680851 (875 4750);
PAINT MONO (875 4750);
DISPLAY INVISIBLE (875 4750);
FORCEPROP 0 LAST CDS_SEC 2
J 0
(875 4750);
DISPLAY 1.021277 (875 4750);
DISPLAY INVISIBLE (875 4750);
FORCEPROP 1 LAST PATH I178
J 0
(1475 3175);
DISPLAY 0.723404 (1475 3175);
PAINT GREEN (1475 3175);
DISPLAY INVISIBLE (1475 3175);
FORCEADD Q_RES..1
(-2975 1450);
FORCEPROP 1 LAST PART_NUMBER CS04992FB07
J 0
(-2875 1425);
DISPLAY 0.404255 (-2875 1425);
DISPLAY INVISIBLE (-2875 1425);
FORCEPROP 1 LAST VALUE 49.9
J 2
(-2750 1450);
DISPLAY 0.510638 (-2750 1450);
FORCEPROP 1 LAST MATERIAL CHIP
J 0
(-2875 1400);
DISPLAY 0.404255 (-2875 1400);
FORCEPROP 1 LAST $LOCATION R3890
J 0
(-3225 1450);
DISPLAY 0.638298 (-3225 1450);
FORCEPROP 1 LASTPIN (-3075 1450) $PN 1
J 0
(-3063 1462);
DISPLAY 0.787234 (-3063 1462);
PAINT MONO (-3063 1462);
FORCEPROP 1 LASTPIN (-2875 1450) $PN 2
J 0
(-2913 1462);
DISPLAY 0.787234 (-2913 1462);
PAINT MONO (-2913 1462);
FORCEPROP 2 LAST CDS_LIB pure_quanta
J 0
(-2975 1450);
DISPLAY INVISIBLE (-2975 1450);
FORCEPROP 1 LAST PACK_TYPE 0402LF
J 0
(-2675 1450);
DISPLAY 0.510638 (-2675 1450);
DISPLAY INVISIBLE (-2675 1450);
FORCEPROP 1 LAST TOLERANCE 1%
J 0
(-2750 1450);
DISPLAY 0.510638 (-2750 1450);
DISPLAY INVISIBLE (-2750 1450);
FORCEPROP 1 LAST WATTAGE 1/16W
J 2
(-2675 1400);
DISPLAY 0.404255 (-2675 1400);
DISPLAY INVISIBLE (-2675 1400);
FORCEPROP 0 LAST CDS_LOCATION R3890
J 0
(-3125 1500);
DISPLAY 1.021277 (-3125 1500);
DISPLAY INVISIBLE (-3125 1500);
FORCEPROP 0 LAST $SEC 1
J 0
(-3125 1500);
DISPLAY 0.680851 (-3125 1500);
PAINT MONO (-3125 1500);
DISPLAY INVISIBLE (-3125 1500);
FORCEPROP 0 LAST CDS_SEC 1
J 0
(-3125 1500);
DISPLAY 1.021277 (-3125 1500);
DISPLAY INVISIBLE (-3125 1500);
FORCEPROP 1 LAST PATH I179
J 0
(-3025 1600);
DISPLAY 0.978723 (-3025 1600);
PAINT WHITE (-3025 1600);
DISPLAY INVISIBLE (-3025 1600);
FORCEADD OFFPAGE..1
(-2925 3050);
FORCEPROP 2 LAST $XR0 27 
J 0
(-3146 3050);
DISPLAY 0.638298 (-3146 3050);
PAINT MONO (-3146 3050);
FORCEPROP 2 LAST CDS_LIB standard
J 0
(-2925 3050);
PAINT MONO (-2925 3050);
DISPLAY INVISIBLE (-2925 3050);
FORCEPROP 1 LAST OFFPAGE TRUE
J 0
(-2600 2925);
DISPLAY 0.872340 (-2600 2925);
DISPLAY INVISIBLE (-2600 2925);
FORCEPROP 1 LAST COMMENT_BODY TRUE
J 0
(-2800 2950);
DISPLAY 0.872340 (-2800 2950);
PAINT GREEN (-2800 2950);
DISPLAY INVISIBLE (-2800 2950);
FORCEPROP 2 LAST PATH I18
J 0
(-2875 3125);
DISPLAY 1.021277 (-2875 3125);
DISPLAY INVISIBLE (-2875 3125);
FORCEADD OFFPAGE..1
(-1775 1400);
FORCEPROP 2 LAST $XR7 96 
J 0
(-2657 1400);
DISPLAY 0.638298 (-2657 1400);
PAINT MONO (-2657 1400);
FORCEPROP 2 LAST $XR6 95 
J 0
(-2567 1400);
DISPLAY 0.638298 (-2567 1400);
PAINT MONO (-2567 1400);
FORCEPROP 2 LAST $XR5 94 
J 0
(-2477 1400);
DISPLAY 0.638298 (-2477 1400);
PAINT MONO (-2477 1400);
FORCEPROP 2 LAST $XR4 93 
J 0
(-2387 1400);
DISPLAY 0.638298 (-2387 1400);
PAINT MONO (-2387 1400);
FORCEPROP 2 LAST $XR3 92 
J 0
(-2297 1400);
DISPLAY 0.638298 (-2297 1400);
PAINT MONO (-2297 1400);
FORCEPROP 2 LAST $XR2 91 
J 0
(-2207 1400);
DISPLAY 0.638298 (-2207 1400);
PAINT MONO (-2207 1400);
FORCEPROP 2 LAST $XR1 90 
J 0
(-2117 1400);
DISPLAY 0.638298 (-2117 1400);
PAINT MONO (-2117 1400);
FORCEPROP 2 LAST $XR0 229 
J 0
(-2027 1400);
DISPLAY 0.638298 (-2027 1400);
PAINT MONO (-2027 1400);
FORCEPROP 2 LAST CDS_LIB standard
J 2
(-1775 1400);
DISPLAY INVISIBLE (-1775 1400);
FORCEPROP 1 LAST OFFPAGE TRUE
J 0
(-1450 1275);
DISPLAY 0.872340 (-1450 1275);
DISPLAY INVISIBLE (-1450 1275);
FORCEPROP 1 LAST COMMENT_BODY TRUE
J 0
(-1650 1300);
DISPLAY 0.872340 (-1650 1300);
PAINT GREEN (-1650 1300);
DISPLAY INVISIBLE (-1650 1300);
FORCEPROP 2 LAST PATH I180
J 2
(-1950 1475);
DISPLAY 1.021277 (-1950 1475);
DISPLAY INVISIBLE (-1950 1475);
FORCEADD OFFPAGE..1
(-2925 3150);
FORCEPROP 2 LAST $XR0 27 
J 0
(-3146 3150);
DISPLAY 0.638298 (-3146 3150);
PAINT MONO (-3146 3150);
FORCEPROP 2 LAST CDS_LIB standard
J 0
(-2925 3150);
PAINT MONO (-2925 3150);
DISPLAY INVISIBLE (-2925 3150);
FORCEPROP 1 LAST OFFPAGE TRUE
J 0
(-2600 3025);
DISPLAY 0.872340 (-2600 3025);
DISPLAY INVISIBLE (-2600 3025);
FORCEPROP 1 LAST COMMENT_BODY TRUE
J 0
(-2800 3050);
DISPLAY 0.872340 (-2800 3050);
PAINT GREEN (-2800 3050);
DISPLAY INVISIBLE (-2800 3050);
FORCEPROP 2 LAST PATH I19
J 0
(-2875 3225);
DISPLAY 1.021277 (-2875 3225);
DISPLAY INVISIBLE (-2875 3225);
FORCEADD OFFPAGE..2
R 2
(-2925 750);
FORCEPROP 2 LAST $XR0 27 
J 0
(-3149 750);
DISPLAY 0.638298 (-3149 750);
PAINT MONO (-3149 750);
FORCEPROP 2 LAST CDS_LIB standard
J 0
(-2925 750);
PAINT MONO (-2925 750);
DISPLAY INVISIBLE (-2925 750);
FORCEPROP 1 LAST OFFPAGE TRUE
J 2
(-3250 625);
DISPLAY 0.872340 (-3250 625);
DISPLAY INVISIBLE (-3250 625);
FORCEPROP 1 LAST COMMENT_BODY TRUE
J 2
(-2880 655);
DISPLAY 0.872340 (-2880 655);
PAINT GREEN (-2880 655);
DISPLAY INVISIBLE (-2880 655);
FORCEPROP 2 LAST PATH I2
J 0
(-2875 825);
DISPLAY 1.021277 (-2875 825);
DISPLAY INVISIBLE (-2875 825);
FORCEADD OFFPAGE..1
(-2925 3200);
FORCEPROP 2 LAST $XR0 27 
J 0
(-3146 3200);
DISPLAY 0.638298 (-3146 3200);
PAINT MONO (-3146 3200);
FORCEPROP 2 LAST CDS_LIB standard
J 0
(-2925 3200);
PAINT MONO (-2925 3200);
DISPLAY INVISIBLE (-2925 3200);
FORCEPROP 1 LAST OFFPAGE TRUE
J 0
(-2600 3075);
DISPLAY 0.872340 (-2600 3075);
DISPLAY INVISIBLE (-2600 3075);
FORCEPROP 1 LAST COMMENT_BODY TRUE
J 0
(-2800 3100);
DISPLAY 0.872340 (-2800 3100);
PAINT GREEN (-2800 3100);
DISPLAY INVISIBLE (-2800 3100);
FORCEPROP 2 LAST PATH I20
J 0
(-2875 3275);
DISPLAY 1.021277 (-2875 3275);
DISPLAY INVISIBLE (-2875 3275);
FORCEADD OFFPAGE..1
(-2925 3300);
FORCEPROP 2 LAST $XR1 96 
J 0
(-3236 3300);
DISPLAY 0.638298 (-3236 3300);
PAINT MONO (-3236 3300);
FORCEPROP 2 LAST $XR0 27 
J 0
(-3146 3300);
DISPLAY 0.638298 (-3146 3300);
PAINT MONO (-3146 3300);
FORCEPROP 2 LAST CDS_LIB standard
J 0
(-2925 3300);
PAINT MONO (-2925 3300);
DISPLAY INVISIBLE (-2925 3300);
FORCEPROP 1 LAST OFFPAGE TRUE
J 0
(-2600 3175);
DISPLAY 0.872340 (-2600 3175);
DISPLAY INVISIBLE (-2600 3175);
FORCEPROP 1 LAST COMMENT_BODY TRUE
J 0
(-2800 3200);
DISPLAY 0.872340 (-2800 3200);
PAINT GREEN (-2800 3200);
DISPLAY INVISIBLE (-2800 3200);
FORCEPROP 2 LAST PATH I21
J 0
(-2875 3375);
DISPLAY 1.021277 (-2875 3375);
DISPLAY INVISIBLE (-2875 3375);
FORCEADD OFFPAGE..1
(-2925 3350);
FORCEPROP 2 LAST $XR1 96 
J 0
(-3236 3350);
DISPLAY 0.638298 (-3236 3350);
PAINT MONO (-3236 3350);
FORCEPROP 2 LAST $XR0 27 
J 0
(-3146 3350);
DISPLAY 0.638298 (-3146 3350);
PAINT MONO (-3146 3350);
FORCEPROP 2 LAST CDS_LIB standard
J 0
(-2925 3350);
PAINT MONO (-2925 3350);
DISPLAY INVISIBLE (-2925 3350);
FORCEPROP 1 LAST OFFPAGE TRUE
J 0
(-2600 3225);
DISPLAY 0.872340 (-2600 3225);
DISPLAY INVISIBLE (-2600 3225);
FORCEPROP 1 LAST COMMENT_BODY TRUE
J 0
(-2800 3250);
DISPLAY 0.872340 (-2800 3250);
PAINT GREEN (-2800 3250);
DISPLAY INVISIBLE (-2800 3250);
FORCEPROP 2 LAST PATH I22
J 0
(-2875 3425);
DISPLAY 1.021277 (-2875 3425);
DISPLAY INVISIBLE (-2875 3425);
FORCEADD OFFPAGE..1
(-2925 3800);
FORCEPROP 2 LAST $XR1 96 
J 0
(-3236 3800);
DISPLAY 0.638298 (-3236 3800);
PAINT MONO (-3236 3800);
FORCEPROP 2 LAST $XR0 27 
J 0
(-3146 3800);
DISPLAY 0.638298 (-3146 3800);
PAINT MONO (-3146 3800);
FORCEPROP 2 LAST CDS_LIB standard
J 0
(-2925 3800);
PAINT MONO (-2925 3800);
DISPLAY INVISIBLE (-2925 3800);
FORCEPROP 1 LAST OFFPAGE TRUE
J 0
(-2600 3675);
DISPLAY 0.872340 (-2600 3675);
DISPLAY INVISIBLE (-2600 3675);
FORCEPROP 1 LAST COMMENT_BODY TRUE
J 0
(-2800 3700);
DISPLAY 0.872340 (-2800 3700);
PAINT GREEN (-2800 3700);
DISPLAY INVISIBLE (-2800 3700);
FORCEPROP 2 LAST PATH I23
J 0
(-2875 3875);
DISPLAY 1.021277 (-2875 3875);
DISPLAY INVISIBLE (-2875 3875);
FORCEADD OFFPAGE..1
(-2925 4200);
FORCEPROP 2 LAST $XR1 96 
J 0
(-3236 4200);
DISPLAY 0.638298 (-3236 4200);
PAINT MONO (-3236 4200);
FORCEPROP 2 LAST $XR0 27 
J 0
(-3146 4200);
DISPLAY 0.638298 (-3146 4200);
PAINT MONO (-3146 4200);
FORCEPROP 2 LAST CDS_LIB standard
J 0
(-2925 4200);
PAINT MONO (-2925 4200);
DISPLAY INVISIBLE (-2925 4200);
FORCEPROP 1 LAST OFFPAGE TRUE
J 0
(-2600 4075);
DISPLAY 0.872340 (-2600 4075);
DISPLAY INVISIBLE (-2600 4075);
FORCEPROP 1 LAST COMMENT_BODY TRUE
J 0
(-2800 4100);
DISPLAY 0.872340 (-2800 4100);
PAINT GREEN (-2800 4100);
DISPLAY INVISIBLE (-2800 4100);
FORCEPROP 2 LAST PATH I24
J 0
(-2875 4275);
DISPLAY 1.021277 (-2875 4275);
DISPLAY INVISIBLE (-2875 4275);
FORCEADD VCC_CORE..1
(-2825 2050);
FORCEPROP 3 LASTPIN (-2825 2000) SIG_NAME P3V3_AUX\g
J 0
(-2815 2010);
DISPLAY 0.659574 (-2815 2010);
PAINT MONO (-2815 2010);
DISPLAY INVISIBLE (-2815 2010);
FORCEPROP 1 LAST HDL_POWER P3V3_AUX
J 1
(-2825 2100);
DISPLAY 1.148936 (-2825 2100);
PAINT GREEN (-2825 2100);
FORCEPROP 2 LAST CDS_LIB logical_power
J 0
(-2825 2050);
PAINT MONO (-2825 2050);
DISPLAY INVISIBLE (-2825 2050);
FORCEPROP 1 LAST PATH I25
J 0
(-2775 2075);
DISPLAY 0.872340 (-2775 2075);
PAINT AQUA (-2775 2075);
DISPLAY INVISIBLE (-2775 2075);
FORCEADD TAP..1
R 2
(-2000 1975);
FORCEPROP 3 LASTPIN (-1950 1975) SIG_NAME M_H_CPU0_SB_CB<0>
J 0
(-1940 1985);
DISPLAY 0.659574 (-1940 1985);
PAINT MONO (-1940 1985);
DISPLAY INVISIBLE (-1940 1985);
FORCEPROP 1 LASTPIN (-1950 1975) BN 0
J 2
(-1938 1983);
DISPLAY 0.680851 (-1938 1983);
PAINT GREEN (-1938 1983);
FORCEPROP 2 LAST CDS_LIB standard
J 0
(-2000 1975);
PAINT MONO (-2000 1975);
DISPLAY INVISIBLE (-2000 1975);
FORCEPROP 1 LAST BODY_TYPE PLUMBING
J 2
(-2000 2025);
DISPLAY 0.872340 (-2000 2025);
PAINT GREEN (-2000 2025);
DISPLAY INVISIBLE (-2000 2025);
FORCEPROP 1 LAST HDL_TAP TRUE
J 2
(-2325 1850);
DISPLAY 0.872340 (-2325 1850);
DISPLAY INVISIBLE (-2325 1850);
FORCEPROP 1 LAST PATH I26
J 2
(-1998 1975);
DISPLAY 0.872340 (-1998 1975);
PAINT GREEN (-1998 1975);
DISPLAY INVISIBLE (-1998 1975);
FORCEADD TAP..1
R 2
(-2000 2075);
FORCEPROP 3 LASTPIN (-1950 2075) SIG_NAME M_H_CPU0_SB_CB<2>
J 0
(-1940 2085);
DISPLAY 0.659574 (-1940 2085);
PAINT MONO (-1940 2085);
DISPLAY INVISIBLE (-1940 2085);
FORCEPROP 1 LASTPIN (-1950 2075) BN 2
J 2
(-1938 2083);
DISPLAY 0.680851 (-1938 2083);
PAINT GREEN (-1938 2083);
FORCEPROP 2 LAST CDS_LIB standard
J 0
(-2000 2075);
DISPLAY INVISIBLE (-2000 2075);
FORCEPROP 1 LAST BODY_TYPE PLUMBING
J 2
(-2000 2125);
DISPLAY 0.872340 (-2000 2125);
PAINT GREEN (-2000 2125);
DISPLAY INVISIBLE (-2000 2125);
FORCEPROP 1 LAST HDL_TAP TRUE
J 2
(-2325 1950);
DISPLAY 0.872340 (-2325 1950);
DISPLAY INVISIBLE (-2325 1950);
FORCEPROP 1 LAST PATH I27
J 2
(-1998 2075);
DISPLAY 0.872340 (-1998 2075);
PAINT GREEN (-1998 2075);
DISPLAY INVISIBLE (-1998 2075);
FORCEADD TAP..1
R 2
(-2000 2025);
FORCEPROP 3 LASTPIN (-1950 2025) SIG_NAME M_H_CPU0_SB_CB<1>
J 0
(-1940 2035);
DISPLAY 0.659574 (-1940 2035);
PAINT MONO (-1940 2035);
DISPLAY INVISIBLE (-1940 2035);
FORCEPROP 1 LASTPIN (-1950 2025) BN 1
J 2
(-1938 2033);
DISPLAY 0.680851 (-1938 2033);
PAINT GREEN (-1938 2033);
FORCEPROP 2 LAST CDS_LIB standard
J 0
(-2000 2025);
DISPLAY INVISIBLE (-2000 2025);
FORCEPROP 1 LAST BODY_TYPE PLUMBING
J 2
(-2000 2075);
DISPLAY 0.872340 (-2000 2075);
PAINT GREEN (-2000 2075);
DISPLAY INVISIBLE (-2000 2075);
FORCEPROP 1 LAST HDL_TAP TRUE
J 2
(-2325 1900);
DISPLAY 0.872340 (-2325 1900);
DISPLAY INVISIBLE (-2325 1900);
FORCEPROP 1 LAST PATH I28
J 2
(-1998 2025);
DISPLAY 0.872340 (-1998 2025);
PAINT GREEN (-1998 2025);
DISPLAY INVISIBLE (-1998 2025);
FORCEADD TAP..1
R 2
(-2000 2125);
FORCEPROP 3 LASTPIN (-1950 2125) SIG_NAME M_H_CPU0_SB_CB<3>
J 0
(-1940 2135);
DISPLAY 0.659574 (-1940 2135);
PAINT MONO (-1940 2135);
DISPLAY INVISIBLE (-1940 2135);
FORCEPROP 1 LASTPIN (-1950 2125) BN 3
J 2
(-1938 2133);
DISPLAY 0.680851 (-1938 2133);
PAINT GREEN (-1938 2133);
FORCEPROP 2 LAST CDS_LIB standard
J 0
(-2000 2125);
DISPLAY INVISIBLE (-2000 2125);
FORCEPROP 1 LAST BODY_TYPE PLUMBING
J 2
(-2000 2175);
DISPLAY 0.872340 (-2000 2175);
PAINT GREEN (-2000 2175);
DISPLAY INVISIBLE (-2000 2175);
FORCEPROP 1 LAST HDL_TAP TRUE
J 2
(-2325 2000);
DISPLAY 0.872340 (-2325 2000);
DISPLAY INVISIBLE (-2325 2000);
FORCEPROP 1 LAST PATH I29
J 2
(-1998 2125);
DISPLAY 0.872340 (-1998 2125);
PAINT GREEN (-1998 2125);
DISPLAY INVISIBLE (-1998 2125);
FORCEADD OFFPAGE..2
R 2
(-2925 700);
FORCEPROP 2 LAST $XR0 27 
J 0
(-3149 700);
DISPLAY 0.638298 (-3149 700);
PAINT MONO (-3149 700);
FORCEPROP 2 LAST CDS_LIB standard
J 0
(-2925 700);
PAINT MONO (-2925 700);
DISPLAY INVISIBLE (-2925 700);
FORCEPROP 1 LAST OFFPAGE TRUE
J 2
(-3250 575);
DISPLAY 0.872340 (-3250 575);
DISPLAY INVISIBLE (-3250 575);
FORCEPROP 1 LAST COMMENT_BODY TRUE
J 2
(-2880 605);
DISPLAY 0.872340 (-2880 605);
PAINT GREEN (-2880 605);
DISPLAY INVISIBLE (-2880 605);
FORCEPROP 2 LAST PATH I3
J 0
(-2875 775);
DISPLAY 1.021277 (-2875 775);
DISPLAY INVISIBLE (-2875 775);
FORCEADD TAP..1
R 2
(-2000 2225);
FORCEPROP 3 LASTPIN (-1950 2225) SIG_NAME M_H_CPU0_SB_CB<5>
J 0
(-1940 2235);
DISPLAY 0.659574 (-1940 2235);
PAINT MONO (-1940 2235);
DISPLAY INVISIBLE (-1940 2235);
FORCEPROP 1 LASTPIN (-1950 2225) BN 5
J 2
(-1938 2233);
DISPLAY 0.680851 (-1938 2233);
PAINT GREEN (-1938 2233);
FORCEPROP 2 LAST CDS_LIB standard
J 0
(-2000 2225);
DISPLAY INVISIBLE (-2000 2225);
FORCEPROP 1 LAST BODY_TYPE PLUMBING
J 2
(-2000 2275);
DISPLAY 0.872340 (-2000 2275);
PAINT GREEN (-2000 2275);
DISPLAY INVISIBLE (-2000 2275);
FORCEPROP 1 LAST HDL_TAP TRUE
J 2
(-2325 2100);
DISPLAY 0.872340 (-2325 2100);
DISPLAY INVISIBLE (-2325 2100);
FORCEPROP 1 LAST PATH I30
J 2
(-1998 2225);
DISPLAY 0.872340 (-1998 2225);
PAINT GREEN (-1998 2225);
DISPLAY INVISIBLE (-1998 2225);
FORCEADD TAP..1
R 2
(-2000 2175);
FORCEPROP 3 LASTPIN (-1950 2175) SIG_NAME M_H_CPU0_SB_CB<4>
J 0
(-1940 2185);
DISPLAY 0.659574 (-1940 2185);
PAINT MONO (-1940 2185);
DISPLAY INVISIBLE (-1940 2185);
FORCEPROP 1 LASTPIN (-1950 2175) BN 4
J 2
(-1938 2183);
DISPLAY 0.680851 (-1938 2183);
PAINT GREEN (-1938 2183);
FORCEPROP 2 LAST CDS_LIB standard
J 0
(-2000 2175);
DISPLAY INVISIBLE (-2000 2175);
FORCEPROP 1 LAST BODY_TYPE PLUMBING
J 2
(-2000 2225);
DISPLAY 0.872340 (-2000 2225);
PAINT GREEN (-2000 2225);
DISPLAY INVISIBLE (-2000 2225);
FORCEPROP 1 LAST HDL_TAP TRUE
J 2
(-2325 2050);
DISPLAY 0.872340 (-2325 2050);
DISPLAY INVISIBLE (-2325 2050);
FORCEPROP 1 LAST PATH I31
J 2
(-1998 2175);
DISPLAY 0.872340 (-1998 2175);
PAINT GREEN (-1998 2175);
DISPLAY INVISIBLE (-1998 2175);
FORCEADD TAP..1
R 2
(-2000 2275);
FORCEPROP 3 LASTPIN (-1950 2275) SIG_NAME M_H_CPU0_SB_CB<6>
J 0
(-1940 2285);
DISPLAY 0.659574 (-1940 2285);
PAINT MONO (-1940 2285);
DISPLAY INVISIBLE (-1940 2285);
FORCEPROP 1 LASTPIN (-1950 2275) BN 6
J 2
(-1938 2283);
DISPLAY 0.680851 (-1938 2283);
PAINT GREEN (-1938 2283);
FORCEPROP 2 LAST CDS_LIB standard
J 0
(-2000 2275);
DISPLAY INVISIBLE (-2000 2275);
FORCEPROP 1 LAST BODY_TYPE PLUMBING
J 2
(-2000 2325);
DISPLAY 0.872340 (-2000 2325);
PAINT GREEN (-2000 2325);
DISPLAY INVISIBLE (-2000 2325);
FORCEPROP 1 LAST HDL_TAP TRUE
J 2
(-2325 2150);
DISPLAY 0.872340 (-2325 2150);
DISPLAY INVISIBLE (-2325 2150);
FORCEPROP 1 LAST PATH I32
J 2
(-1998 2275);
DISPLAY 0.872340 (-1998 2275);
PAINT GREEN (-1998 2275);
DISPLAY INVISIBLE (-1998 2275);
FORCEADD TAP..1
R 2
(-2000 2325);
FORCEPROP 3 LASTPIN (-1950 2325) SIG_NAME M_H_CPU0_SB_CB<7>
J 0
(-1940 2335);
DISPLAY 0.659574 (-1940 2335);
PAINT MONO (-1940 2335);
DISPLAY INVISIBLE (-1940 2335);
FORCEPROP 1 LASTPIN (-1950 2325) BN 7
J 2
(-1938 2333);
DISPLAY 0.680851 (-1938 2333);
PAINT GREEN (-1938 2333);
FORCEPROP 2 LAST CDS_LIB standard
J 0
(-2000 2325);
DISPLAY INVISIBLE (-2000 2325);
FORCEPROP 1 LAST BODY_TYPE PLUMBING
J 2
(-2000 2375);
DISPLAY 0.872340 (-2000 2375);
PAINT GREEN (-2000 2375);
DISPLAY INVISIBLE (-2000 2375);
FORCEPROP 1 LAST HDL_TAP TRUE
J 2
(-2325 2200);
DISPLAY 0.872340 (-2325 2200);
DISPLAY INVISIBLE (-2325 2200);
FORCEPROP 1 LAST PATH I33
J 2
(-1998 2325);
DISPLAY 0.872340 (-1998 2325);
PAINT GREEN (-1998 2325);
DISPLAY INVISIBLE (-1998 2325);
FORCEADD TAP..1
R 2
(-2000 2425);
FORCEPROP 3 LASTPIN (-1950 2425) SIG_NAME M_H_CPU0_SA_CB<0>
J 0
(-1940 2435);
DISPLAY 0.659574 (-1940 2435);
PAINT MONO (-1940 2435);
DISPLAY INVISIBLE (-1940 2435);
FORCEPROP 1 LASTPIN (-1950 2425) BN 0
J 2
(-1938 2433);
DISPLAY 0.680851 (-1938 2433);
PAINT GREEN (-1938 2433);
FORCEPROP 2 LAST CDS_LIB standard
J 0
(-2000 2425);
PAINT MONO (-2000 2425);
DISPLAY INVISIBLE (-2000 2425);
FORCEPROP 1 LAST BODY_TYPE PLUMBING
J 2
(-2000 2475);
DISPLAY 0.872340 (-2000 2475);
PAINT GREEN (-2000 2475);
DISPLAY INVISIBLE (-2000 2475);
FORCEPROP 1 LAST HDL_TAP TRUE
J 2
(-2325 2300);
DISPLAY 0.872340 (-2325 2300);
DISPLAY INVISIBLE (-2325 2300);
FORCEPROP 1 LAST PATH I34
J 2
(-1998 2425);
DISPLAY 0.872340 (-1998 2425);
PAINT GREEN (-1998 2425);
DISPLAY INVISIBLE (-1998 2425);
FORCEADD TAP..1
R 2
(-2000 2475);
FORCEPROP 3 LASTPIN (-1950 2475) SIG_NAME M_H_CPU0_SA_CB<1>
J 0
(-1940 2485);
DISPLAY 0.659574 (-1940 2485);
PAINT MONO (-1940 2485);
DISPLAY INVISIBLE (-1940 2485);
FORCEPROP 1 LASTPIN (-1950 2475) BN 1
J 2
(-1938 2483);
DISPLAY 0.680851 (-1938 2483);
PAINT GREEN (-1938 2483);
FORCEPROP 2 LAST CDS_LIB standard
J 0
(-2000 2475);
DISPLAY INVISIBLE (-2000 2475);
FORCEPROP 1 LAST BODY_TYPE PLUMBING
J 2
(-2000 2525);
DISPLAY 0.872340 (-2000 2525);
PAINT GREEN (-2000 2525);
DISPLAY INVISIBLE (-2000 2525);
FORCEPROP 1 LAST HDL_TAP TRUE
J 2
(-2325 2350);
DISPLAY 0.872340 (-2325 2350);
DISPLAY INVISIBLE (-2325 2350);
FORCEPROP 1 LAST PATH I35
J 2
(-1998 2475);
DISPLAY 0.872340 (-1998 2475);
PAINT GREEN (-1998 2475);
DISPLAY INVISIBLE (-1998 2475);
FORCEADD TAP..1
R 2
(-2000 2575);
FORCEPROP 3 LASTPIN (-1950 2575) SIG_NAME M_H_CPU0_SA_CB<3>
J 0
(-1940 2585);
DISPLAY 0.659574 (-1940 2585);
PAINT MONO (-1940 2585);
DISPLAY INVISIBLE (-1940 2585);
FORCEPROP 1 LASTPIN (-1950 2575) BN 3
J 2
(-1938 2583);
DISPLAY 0.680851 (-1938 2583);
PAINT GREEN (-1938 2583);
FORCEPROP 2 LAST CDS_LIB standard
J 0
(-2000 2575);
DISPLAY INVISIBLE (-2000 2575);
FORCEPROP 1 LAST BODY_TYPE PLUMBING
J 2
(-2000 2625);
DISPLAY 0.872340 (-2000 2625);
PAINT GREEN (-2000 2625);
DISPLAY INVISIBLE (-2000 2625);
FORCEPROP 1 LAST HDL_TAP TRUE
J 2
(-2325 2450);
DISPLAY 0.872340 (-2325 2450);
DISPLAY INVISIBLE (-2325 2450);
FORCEPROP 1 LAST PATH I36
J 2
(-1998 2575);
DISPLAY 0.872340 (-1998 2575);
PAINT GREEN (-1998 2575);
DISPLAY INVISIBLE (-1998 2575);
FORCEADD TAP..1
R 2
(-2000 2525);
FORCEPROP 3 LASTPIN (-1950 2525) SIG_NAME M_H_CPU0_SA_CB<2>
J 0
(-1940 2535);
DISPLAY 0.659574 (-1940 2535);
PAINT MONO (-1940 2535);
DISPLAY INVISIBLE (-1940 2535);
FORCEPROP 1 LASTPIN (-1950 2525) BN 2
J 2
(-1938 2533);
DISPLAY 0.680851 (-1938 2533);
PAINT GREEN (-1938 2533);
FORCEPROP 2 LAST CDS_LIB standard
J 0
(-2000 2525);
DISPLAY INVISIBLE (-2000 2525);
FORCEPROP 1 LAST BODY_TYPE PLUMBING
J 2
(-2000 2575);
DISPLAY 0.872340 (-2000 2575);
PAINT GREEN (-2000 2575);
DISPLAY INVISIBLE (-2000 2575);
FORCEPROP 1 LAST HDL_TAP TRUE
J 2
(-2325 2400);
DISPLAY 0.872340 (-2325 2400);
DISPLAY INVISIBLE (-2325 2400);
FORCEPROP 1 LAST PATH I37
J 2
(-1998 2525);
DISPLAY 0.872340 (-1998 2525);
PAINT GREEN (-1998 2525);
DISPLAY INVISIBLE (-1998 2525);
FORCEADD TAP..1
R 2
(-2000 2625);
FORCEPROP 3 LASTPIN (-1950 2625) SIG_NAME M_H_CPU0_SA_CB<4>
J 0
(-1940 2635);
DISPLAY 0.659574 (-1940 2635);
PAINT MONO (-1940 2635);
DISPLAY INVISIBLE (-1940 2635);
FORCEPROP 1 LASTPIN (-1950 2625) BN 4
J 2
(-1938 2633);
DISPLAY 0.680851 (-1938 2633);
PAINT GREEN (-1938 2633);
FORCEPROP 2 LAST CDS_LIB standard
J 0
(-2000 2625);
DISPLAY INVISIBLE (-2000 2625);
FORCEPROP 1 LAST BODY_TYPE PLUMBING
J 2
(-2000 2675);
DISPLAY 0.872340 (-2000 2675);
PAINT GREEN (-2000 2675);
DISPLAY INVISIBLE (-2000 2675);
FORCEPROP 1 LAST HDL_TAP TRUE
J 2
(-2325 2500);
DISPLAY 0.872340 (-2325 2500);
DISPLAY INVISIBLE (-2325 2500);
FORCEPROP 1 LAST PATH I38
J 2
(-1998 2625);
DISPLAY 0.872340 (-1998 2625);
PAINT GREEN (-1998 2625);
DISPLAY INVISIBLE (-1998 2625);
FORCEADD TAP..1
R 2
(-2000 2725);
FORCEPROP 3 LASTPIN (-1950 2725) SIG_NAME M_H_CPU0_SA_CB<6>
J 0
(-1940 2735);
DISPLAY 0.659574 (-1940 2735);
PAINT MONO (-1940 2735);
DISPLAY INVISIBLE (-1940 2735);
FORCEPROP 1 LASTPIN (-1950 2725) BN 6
J 2
(-1938 2733);
DISPLAY 0.680851 (-1938 2733);
PAINT GREEN (-1938 2733);
FORCEPROP 2 LAST CDS_LIB standard
J 0
(-2000 2725);
DISPLAY INVISIBLE (-2000 2725);
FORCEPROP 1 LAST BODY_TYPE PLUMBING
J 2
(-2000 2775);
DISPLAY 0.872340 (-2000 2775);
PAINT GREEN (-2000 2775);
DISPLAY INVISIBLE (-2000 2775);
FORCEPROP 1 LAST HDL_TAP TRUE
J 2
(-2325 2600);
DISPLAY 0.872340 (-2325 2600);
DISPLAY INVISIBLE (-2325 2600);
FORCEPROP 1 LAST PATH I39
J 2
(-1998 2725);
DISPLAY 0.872340 (-1998 2725);
PAINT GREEN (-1998 2725);
DISPLAY INVISIBLE (-1998 2725);
FORCEADD UNIVERSAL_GND..1
(-1775 -200);
FORCEPROP 3 LASTPIN (-1775 -150) SIG_NAME GND\g
J 0
(-1765 -140);
DISPLAY 0.659574 (-1765 -140);
PAINT MONO (-1765 -140);
DISPLAY INVISIBLE (-1765 -140);
FORCEPROP 2 LAST CDS_LIB logical_power
J 0
(-1775 -200);
PAINT MONO (-1775 -200);
DISPLAY INVISIBLE (-1775 -200);
FORCEPROP 1 LAST HDL_POWER GND
J 1
(-1750 -275);
DISPLAY 0.872340 (-1750 -275);
PAINT GREEN (-1750 -275);
DISPLAY INVISIBLE (-1750 -275);
FORCEPROP 1 LAST PATH I4
J 0
(-1700 -200);
DISPLAY 0.872340 (-1700 -200);
PAINT AQUA (-1700 -200);
DISPLAY INVISIBLE (-1700 -200);
FORCEADD TAP..1
R 2
(-2000 2675);
FORCEPROP 3 LASTPIN (-1950 2675) SIG_NAME M_H_CPU0_SA_CB<5>
J 0
(-1940 2685);
DISPLAY 0.659574 (-1940 2685);
PAINT MONO (-1940 2685);
DISPLAY INVISIBLE (-1940 2685);
FORCEPROP 1 LASTPIN (-1950 2675) BN 5
J 2
(-1938 2683);
DISPLAY 0.680851 (-1938 2683);
PAINT GREEN (-1938 2683);
FORCEPROP 2 LAST CDS_LIB standard
J 0
(-2000 2675);
DISPLAY INVISIBLE (-2000 2675);
FORCEPROP 1 LAST BODY_TYPE PLUMBING
J 2
(-2000 2725);
DISPLAY 0.872340 (-2000 2725);
PAINT GREEN (-2000 2725);
DISPLAY INVISIBLE (-2000 2725);
FORCEPROP 1 LAST HDL_TAP TRUE
J 2
(-2325 2550);
DISPLAY 0.872340 (-2325 2550);
DISPLAY INVISIBLE (-2325 2550);
FORCEPROP 1 LAST PATH I40
J 2
(-1998 2675);
DISPLAY 0.872340 (-1998 2675);
PAINT GREEN (-1998 2675);
DISPLAY INVISIBLE (-1998 2675);
FORCEADD TAP..1
R 2
(-2000 2775);
FORCEPROP 3 LASTPIN (-1950 2775) SIG_NAME M_H_CPU0_SA_CB<7>
J 0
(-1940 2785);
DISPLAY 0.659574 (-1940 2785);
PAINT MONO (-1940 2785);
DISPLAY INVISIBLE (-1940 2785);
FORCEPROP 1 LASTPIN (-1950 2775) BN 7
J 2
(-1938 2783);
DISPLAY 0.680851 (-1938 2783);
PAINT GREEN (-1938 2783);
FORCEPROP 2 LAST CDS_LIB standard
J 0
(-2000 2775);
DISPLAY INVISIBLE (-2000 2775);
FORCEPROP 1 LAST BODY_TYPE PLUMBING
J 2
(-2000 2825);
DISPLAY 0.872340 (-2000 2825);
PAINT GREEN (-2000 2825);
DISPLAY INVISIBLE (-2000 2825);
FORCEPROP 1 LAST HDL_TAP TRUE
J 2
(-2325 2650);
DISPLAY 0.872340 (-2325 2650);
DISPLAY INVISIBLE (-2325 2650);
FORCEPROP 1 LAST PATH I41
J 2
(-1998 2775);
DISPLAY 0.872340 (-1998 2775);
PAINT GREEN (-1998 2775);
DISPLAY INVISIBLE (-1998 2775);
FORCEADD TAP..1
R 2
(-2000 3525);
FORCEPROP 3 LASTPIN (-1950 3525) SIG_NAME M_H_CPU0_SB_CA<1>
J 0
(-1940 3535);
DISPLAY 0.659574 (-1940 3535);
PAINT MONO (-1940 3535);
DISPLAY INVISIBLE (-1940 3535);
FORCEPROP 1 LASTPIN (-1950 3525) BN 1
J 2
(-1938 3533);
DISPLAY 0.680851 (-1938 3533);
PAINT GREEN (-1938 3533);
FORCEPROP 2 LAST CDS_LIB standard
J 0
(-2000 3525);
DISPLAY INVISIBLE (-2000 3525);
FORCEPROP 1 LAST BODY_TYPE PLUMBING
J 2
(-2000 3575);
DISPLAY 0.872340 (-2000 3575);
PAINT GREEN (-2000 3575);
DISPLAY INVISIBLE (-2000 3575);
FORCEPROP 1 LAST HDL_TAP TRUE
J 2
(-2325 3400);
DISPLAY 0.872340 (-2325 3400);
DISPLAY INVISIBLE (-2325 3400);
FORCEPROP 1 LAST PATH I42
J 2
(-1998 3525);
DISPLAY 0.872340 (-1998 3525);
PAINT GREEN (-1998 3525);
DISPLAY INVISIBLE (-1998 3525);
FORCEADD TAP..1
R 2
(-2000 3475);
FORCEPROP 3 LASTPIN (-1950 3475) SIG_NAME M_H_CPU0_SB_CA<0>
J 0
(-1940 3485);
DISPLAY 0.659574 (-1940 3485);
PAINT MONO (-1940 3485);
DISPLAY INVISIBLE (-1940 3485);
FORCEPROP 1 LASTPIN (-1950 3475) BN 0
J 2
(-1938 3483);
DISPLAY 0.680851 (-1938 3483);
PAINT GREEN (-1938 3483);
FORCEPROP 2 LAST CDS_LIB standard
J 0
(-2000 3475);
DISPLAY INVISIBLE (-2000 3475);
FORCEPROP 1 LAST BODY_TYPE PLUMBING
J 2
(-2000 3525);
DISPLAY 0.872340 (-2000 3525);
PAINT GREEN (-2000 3525);
DISPLAY INVISIBLE (-2000 3525);
FORCEPROP 1 LAST HDL_TAP TRUE
J 2
(-2325 3350);
DISPLAY 0.872340 (-2325 3350);
DISPLAY INVISIBLE (-2325 3350);
FORCEPROP 1 LAST PATH I43
J 2
(-1998 3475);
DISPLAY 0.872340 (-1998 3475);
PAINT GREEN (-1998 3475);
DISPLAY INVISIBLE (-1998 3475);
FORCEADD TAP..1
R 2
(-2000 3625);
FORCEPROP 3 LASTPIN (-1950 3625) SIG_NAME M_H_CPU0_SB_CA<3>
J 0
(-1940 3635);
DISPLAY 0.659574 (-1940 3635);
PAINT MONO (-1940 3635);
DISPLAY INVISIBLE (-1940 3635);
FORCEPROP 1 LASTPIN (-1950 3625) BN 3
J 2
(-1938 3633);
DISPLAY 0.680851 (-1938 3633);
PAINT GREEN (-1938 3633);
FORCEPROP 2 LAST CDS_LIB standard
J 0
(-2000 3625);
DISPLAY INVISIBLE (-2000 3625);
FORCEPROP 1 LAST BODY_TYPE PLUMBING
J 2
(-2000 3675);
DISPLAY 0.872340 (-2000 3675);
PAINT GREEN (-2000 3675);
DISPLAY INVISIBLE (-2000 3675);
FORCEPROP 1 LAST HDL_TAP TRUE
J 2
(-2325 3500);
DISPLAY 0.872340 (-2325 3500);
DISPLAY INVISIBLE (-2325 3500);
FORCEPROP 1 LAST PATH I44
J 2
(-1998 3625);
DISPLAY 0.872340 (-1998 3625);
PAINT GREEN (-1998 3625);
DISPLAY INVISIBLE (-1998 3625);
FORCEADD TAP..1
R 2
(-2000 3575);
FORCEPROP 3 LASTPIN (-1950 3575) SIG_NAME M_H_CPU0_SB_CA<2>
J 0
(-1940 3585);
DISPLAY 0.659574 (-1940 3585);
PAINT MONO (-1940 3585);
DISPLAY INVISIBLE (-1940 3585);
FORCEPROP 1 LASTPIN (-1950 3575) BN 2
J 2
(-1938 3583);
DISPLAY 0.680851 (-1938 3583);
PAINT GREEN (-1938 3583);
FORCEPROP 2 LAST CDS_LIB standard
J 0
(-2000 3575);
DISPLAY INVISIBLE (-2000 3575);
FORCEPROP 1 LAST BODY_TYPE PLUMBING
J 2
(-2000 3625);
DISPLAY 0.872340 (-2000 3625);
PAINT GREEN (-2000 3625);
DISPLAY INVISIBLE (-2000 3625);
FORCEPROP 1 LAST HDL_TAP TRUE
J 2
(-2325 3450);
DISPLAY 0.872340 (-2325 3450);
DISPLAY INVISIBLE (-2325 3450);
FORCEPROP 1 LAST PATH I45
J 2
(-1998 3575);
DISPLAY 0.872340 (-1998 3575);
PAINT GREEN (-1998 3575);
DISPLAY INVISIBLE (-1998 3575);
FORCEADD TAP..1
R 2
(-2000 3725);
FORCEPROP 3 LASTPIN (-1950 3725) SIG_NAME M_H_CPU0_SB_CA<5>
J 0
(-1940 3735);
DISPLAY 0.659574 (-1940 3735);
PAINT MONO (-1940 3735);
DISPLAY INVISIBLE (-1940 3735);
FORCEPROP 1 LASTPIN (-1950 3725) BN 5
J 2
(-1938 3733);
DISPLAY 0.680851 (-1938 3733);
PAINT GREEN (-1938 3733);
FORCEPROP 2 LAST CDS_LIB standard
J 0
(-2000 3725);
DISPLAY INVISIBLE (-2000 3725);
FORCEPROP 1 LAST BODY_TYPE PLUMBING
J 2
(-2000 3775);
DISPLAY 0.872340 (-2000 3775);
PAINT GREEN (-2000 3775);
DISPLAY INVISIBLE (-2000 3775);
FORCEPROP 1 LAST HDL_TAP TRUE
J 2
(-2325 3600);
DISPLAY 0.872340 (-2325 3600);
DISPLAY INVISIBLE (-2325 3600);
FORCEPROP 1 LAST PATH I46
J 2
(-1998 3725);
DISPLAY 0.872340 (-1998 3725);
PAINT GREEN (-1998 3725);
DISPLAY INVISIBLE (-1998 3725);
FORCEADD TAP..1
R 2
(-2000 3675);
FORCEPROP 3 LASTPIN (-1950 3675) SIG_NAME M_H_CPU0_SB_CA<4>
J 0
(-1940 3685);
DISPLAY 0.659574 (-1940 3685);
PAINT MONO (-1940 3685);
DISPLAY INVISIBLE (-1940 3685);
FORCEPROP 1 LASTPIN (-1950 3675) BN 4
J 2
(-1938 3683);
DISPLAY 0.680851 (-1938 3683);
PAINT GREEN (-1938 3683);
FORCEPROP 2 LAST CDS_LIB standard
J 0
(-2000 3675);
DISPLAY INVISIBLE (-2000 3675);
FORCEPROP 1 LAST BODY_TYPE PLUMBING
J 2
(-2000 3725);
DISPLAY 0.872340 (-2000 3725);
PAINT GREEN (-2000 3725);
DISPLAY INVISIBLE (-2000 3725);
FORCEPROP 1 LAST HDL_TAP TRUE
J 2
(-2325 3550);
DISPLAY 0.872340 (-2325 3550);
DISPLAY INVISIBLE (-2325 3550);
FORCEPROP 1 LAST PATH I47
J 2
(-1998 3675);
DISPLAY 0.872340 (-1998 3675);
PAINT GREEN (-1998 3675);
DISPLAY INVISIBLE (-1998 3675);
FORCEADD TAP..1
R 2
(-2000 3775);
FORCEPROP 3 LASTPIN (-1950 3775) SIG_NAME M_H_CPU0_SB_CA<6>
J 0
(-1940 3785);
DISPLAY 0.659574 (-1940 3785);
PAINT MONO (-1940 3785);
DISPLAY INVISIBLE (-1940 3785);
FORCEPROP 1 LASTPIN (-1950 3775) BN 6
J 2
(-1938 3783);
DISPLAY 0.680851 (-1938 3783);
PAINT GREEN (-1938 3783);
FORCEPROP 2 LAST CDS_LIB standard
J 0
(-2000 3775);
DISPLAY INVISIBLE (-2000 3775);
FORCEPROP 1 LAST BODY_TYPE PLUMBING
J 2
(-2000 3825);
DISPLAY 0.872340 (-2000 3825);
PAINT GREEN (-2000 3825);
DISPLAY INVISIBLE (-2000 3825);
FORCEPROP 1 LAST HDL_TAP TRUE
J 2
(-2325 3650);
DISPLAY 0.872340 (-2325 3650);
DISPLAY INVISIBLE (-2325 3650);
FORCEPROP 1 LAST PATH I48
J 2
(-1998 3775);
DISPLAY 0.872340 (-1998 3775);
PAINT GREEN (-1998 3775);
DISPLAY INVISIBLE (-1998 3775);
FORCEADD TAP..1
R 2
(-2000 3875);
FORCEPROP 3 LASTPIN (-1950 3875) SIG_NAME M_H_CPU0_SA_CA<0>
J 0
(-1940 3885);
DISPLAY 0.659574 (-1940 3885);
PAINT MONO (-1940 3885);
DISPLAY INVISIBLE (-1940 3885);
FORCEPROP 1 LASTPIN (-1950 3875) BN 0
J 2
(-1938 3883);
DISPLAY 0.680851 (-1938 3883);
PAINT GREEN (-1938 3883);
FORCEPROP 2 LAST CDS_LIB standard
J 0
(-2000 3875);
DISPLAY INVISIBLE (-2000 3875);
FORCEPROP 1 LAST BODY_TYPE PLUMBING
J 2
(-2000 3925);
DISPLAY 0.872340 (-2000 3925);
PAINT GREEN (-2000 3925);
DISPLAY INVISIBLE (-2000 3925);
FORCEPROP 1 LAST HDL_TAP TRUE
J 2
(-2325 3750);
DISPLAY 0.872340 (-2325 3750);
DISPLAY INVISIBLE (-2325 3750);
FORCEPROP 1 LAST PATH I49
J 2
(-1998 3875);
DISPLAY 0.872340 (-1998 3875);
PAINT GREEN (-1998 3875);
DISPLAY INVISIBLE (-1998 3875);
FORCEADD Q_RES..2
(-1775 25);
FORCEPROP 1 LAST PART_NUMBER CS41962FB03
J 0
(-1735 -100);
DISPLAY 0.978723 (-1735 -100);
DISPLAY INVISIBLE (-1735 -100);
FORCEPROP 1 LAST VALUE 196K
J 0
(-1730 100);
DISPLAY 0.978723 (-1730 100);
FORCEPROP 1 LAST MATERIAL CHIP
J 0
(-1735 -50);
DISPLAY 0.978723 (-1735 -50);
FORCEPROP 1 LAST PACK_TYPE 0402LF
J 0
(-1735 -150);
DISPLAY 0.978723 (-1735 -150);
FORCEPROP 1 LAST WATTAGE 1/16W
J 0
(-1735 0);
DISPLAY 0.978723 (-1735 0);
FORCEPROP 1 LAST TOLERANCE 1%
J 0
(-1730 50);
DISPLAY 0.978723 (-1730 50);
FORCEPROP 1 LAST $LOCATION R41
J 0
(-1730 150);
DISPLAY 0.978723 (-1730 150);
FORCEPROP 1 LASTPIN (-1775 125) $PN 1
J 0
(-1770 87);
DISPLAY 0.787234 (-1770 87);
FORCEPROP 1 LASTPIN (-1775 -75) $PN 2
J 0
(-1770 -65);
DISPLAY 0.787234 (-1770 -65);
FORCEPROP 2 LAST CDS_LIB pure_quanta
J 0
(-1775 25);
PAINT MONO (-1775 25);
DISPLAY INVISIBLE (-1775 25);
FORCEPROP 2 LAST CDS_LOCATION R41
J 0
(-1725 250);
DISPLAY 1.021277 (-1725 250);
DISPLAY INVISIBLE (-1725 250);
FORCEPROP 2 LAST $SEC 1
J 0
(-1725 250);
DISPLAY 0.680851 (-1725 250);
PAINT MONO (-1725 250);
DISPLAY INVISIBLE (-1725 250);
FORCEPROP 2 LAST CDS_SEC 1
J 0
(-1725 250);
DISPLAY 1.021277 (-1725 250);
DISPLAY INVISIBLE (-1725 250);
FORCEPROP 1 LAST PATH I5
J 0
(-1725 200);
DISPLAY 0.978723 (-1725 200);
PAINT WHITE (-1725 200);
DISPLAY INVISIBLE (-1725 200);
FORCEADD TAP..1
R 2
(-2000 3925);
FORCEPROP 3 LASTPIN (-1950 3925) SIG_NAME M_H_CPU0_SA_CA<1>
J 0
(-1940 3935);
DISPLAY 0.659574 (-1940 3935);
PAINT MONO (-1940 3935);
DISPLAY INVISIBLE (-1940 3935);
FORCEPROP 1 LASTPIN (-1950 3925) BN 1
J 2
(-1938 3933);
DISPLAY 0.680851 (-1938 3933);
PAINT GREEN (-1938 3933);
FORCEPROP 2 LAST CDS_LIB standard
J 0
(-2000 3925);
DISPLAY INVISIBLE (-2000 3925);
FORCEPROP 1 LAST BODY_TYPE PLUMBING
J 2
(-2000 3975);
DISPLAY 0.872340 (-2000 3975);
PAINT GREEN (-2000 3975);
DISPLAY INVISIBLE (-2000 3975);
FORCEPROP 1 LAST HDL_TAP TRUE
J 2
(-2325 3800);
DISPLAY 0.872340 (-2325 3800);
DISPLAY INVISIBLE (-2325 3800);
FORCEPROP 1 LAST PATH I50
J 2
(-1998 3925);
DISPLAY 0.872340 (-1998 3925);
PAINT GREEN (-1998 3925);
DISPLAY INVISIBLE (-1998 3925);
FORCEADD TAP..1
R 2
(-2000 3975);
FORCEPROP 3 LASTPIN (-1950 3975) SIG_NAME M_H_CPU0_SA_CA<2>
J 0
(-1940 3985);
DISPLAY 0.659574 (-1940 3985);
PAINT MONO (-1940 3985);
DISPLAY INVISIBLE (-1940 3985);
FORCEPROP 1 LASTPIN (-1950 3975) BN 2
J 2
(-1938 3983);
DISPLAY 0.680851 (-1938 3983);
PAINT GREEN (-1938 3983);
FORCEPROP 2 LAST CDS_LIB standard
J 0
(-2000 3975);
DISPLAY INVISIBLE (-2000 3975);
FORCEPROP 1 LAST BODY_TYPE PLUMBING
J 2
(-2000 4025);
DISPLAY 0.872340 (-2000 4025);
PAINT GREEN (-2000 4025);
DISPLAY INVISIBLE (-2000 4025);
FORCEPROP 1 LAST HDL_TAP TRUE
J 2
(-2325 3850);
DISPLAY 0.872340 (-2325 3850);
DISPLAY INVISIBLE (-2325 3850);
FORCEPROP 1 LAST PATH I51
J 2
(-1998 3975);
DISPLAY 0.872340 (-1998 3975);
PAINT GREEN (-1998 3975);
DISPLAY INVISIBLE (-1998 3975);
FORCEADD TAP..1
R 2
(-2000 4025);
FORCEPROP 3 LASTPIN (-1950 4025) SIG_NAME M_H_CPU0_SA_CA<3>
J 0
(-1940 4035);
DISPLAY 0.659574 (-1940 4035);
PAINT MONO (-1940 4035);
DISPLAY INVISIBLE (-1940 4035);
FORCEPROP 1 LASTPIN (-1950 4025) BN 3
J 2
(-1938 4033);
DISPLAY 0.680851 (-1938 4033);
PAINT GREEN (-1938 4033);
FORCEPROP 2 LAST CDS_LIB standard
J 0
(-2000 4025);
DISPLAY INVISIBLE (-2000 4025);
FORCEPROP 1 LAST BODY_TYPE PLUMBING
J 2
(-2000 4075);
DISPLAY 0.872340 (-2000 4075);
PAINT GREEN (-2000 4075);
DISPLAY INVISIBLE (-2000 4075);
FORCEPROP 1 LAST HDL_TAP TRUE
J 2
(-2325 3900);
DISPLAY 0.872340 (-2325 3900);
DISPLAY INVISIBLE (-2325 3900);
FORCEPROP 1 LAST PATH I52
J 2
(-1998 4025);
DISPLAY 0.872340 (-1998 4025);
PAINT GREEN (-1998 4025);
DISPLAY INVISIBLE (-1998 4025);
FORCEADD TAP..1
R 2
(-2000 4125);
FORCEPROP 3 LASTPIN (-1950 4125) SIG_NAME M_H_CPU0_SA_CA<5>
J 0
(-1940 4135);
DISPLAY 0.659574 (-1940 4135);
PAINT MONO (-1940 4135);
DISPLAY INVISIBLE (-1940 4135);
FORCEPROP 1 LASTPIN (-1950 4125) BN 5
J 2
(-1938 4133);
DISPLAY 0.680851 (-1938 4133);
PAINT GREEN (-1938 4133);
FORCEPROP 2 LAST CDS_LIB standard
J 0
(-2000 4125);
DISPLAY INVISIBLE (-2000 4125);
FORCEPROP 1 LAST BODY_TYPE PLUMBING
J 2
(-2000 4175);
DISPLAY 0.872340 (-2000 4175);
PAINT GREEN (-2000 4175);
DISPLAY INVISIBLE (-2000 4175);
FORCEPROP 1 LAST HDL_TAP TRUE
J 2
(-2325 4000);
DISPLAY 0.872340 (-2325 4000);
DISPLAY INVISIBLE (-2325 4000);
FORCEPROP 1 LAST PATH I53
J 2
(-1998 4125);
DISPLAY 0.872340 (-1998 4125);
PAINT GREEN (-1998 4125);
DISPLAY INVISIBLE (-1998 4125);
FORCEADD TAP..1
R 2
(-2000 4075);
FORCEPROP 3 LASTPIN (-1950 4075) SIG_NAME M_H_CPU0_SA_CA<4>
J 0
(-1940 4085);
DISPLAY 0.659574 (-1940 4085);
PAINT MONO (-1940 4085);
DISPLAY INVISIBLE (-1940 4085);
FORCEPROP 1 LASTPIN (-1950 4075) BN 4
J 2
(-1938 4083);
DISPLAY 0.680851 (-1938 4083);
PAINT GREEN (-1938 4083);
FORCEPROP 2 LAST CDS_LIB standard
J 0
(-2000 4075);
DISPLAY INVISIBLE (-2000 4075);
FORCEPROP 1 LAST BODY_TYPE PLUMBING
J 2
(-2000 4125);
DISPLAY 0.872340 (-2000 4125);
PAINT GREEN (-2000 4125);
DISPLAY INVISIBLE (-2000 4125);
FORCEPROP 1 LAST HDL_TAP TRUE
J 2
(-2325 3950);
DISPLAY 0.872340 (-2325 3950);
DISPLAY INVISIBLE (-2325 3950);
FORCEPROP 1 LAST PATH I54
J 2
(-1998 4075);
DISPLAY 0.872340 (-1998 4075);
PAINT GREEN (-1998 4075);
DISPLAY INVISIBLE (-1998 4075);
FORCEADD TAP..1
R 2
(-2000 4175);
FORCEPROP 3 LASTPIN (-1950 4175) SIG_NAME M_H_CPU0_SA_CA<6>
J 0
(-1940 4185);
DISPLAY 0.659574 (-1940 4185);
PAINT MONO (-1940 4185);
DISPLAY INVISIBLE (-1940 4185);
FORCEPROP 1 LASTPIN (-1950 4175) BN 6
J 2
(-1938 4183);
DISPLAY 0.680851 (-1938 4183);
PAINT GREEN (-1938 4183);
FORCEPROP 2 LAST CDS_LIB standard
J 0
(-2000 4175);
DISPLAY INVISIBLE (-2000 4175);
FORCEPROP 1 LAST BODY_TYPE PLUMBING
J 2
(-2000 4225);
DISPLAY 0.872340 (-2000 4225);
PAINT GREEN (-2000 4225);
DISPLAY INVISIBLE (-2000 4225);
FORCEPROP 1 LAST HDL_TAP TRUE
J 2
(-2325 4050);
DISPLAY 0.872340 (-2325 4050);
DISPLAY INVISIBLE (-2325 4050);
FORCEPROP 1 LAST PATH I55
J 2
(-1998 4175);
DISPLAY 0.872340 (-1998 4175);
PAINT GREEN (-1998 4175);
DISPLAY INVISIBLE (-1998 4175);
FORCEADD Q_CAP..1
(1375 300);
FORCEPROP 1 LAST PART_NUMBER CH5221MEB00
J 0
(1425 150);
DISPLAY 0.978723 (1425 150);
DISPLAY INVISIBLE (1425 150);
FORCEPROP 1 LAST MATERIAL X6S
J 0
(1425 200);
DISPLAY 0.978723 (1425 200);
FORCEPROP 1 LAST PACK_TYPE C0402
J 0
(1425 100);
DISPLAY 0.978723 (1425 100);
FORCEPROP 1 LAST TOLERANCE 20%
J 0
(1425 250);
DISPLAY 0.978723 (1425 250);
FORCEPROP 1 LAST VOLTAGE 6.3V
J 0
(1425 300);
DISPLAY 0.978723 (1425 300);
FORCEPROP 1 LAST VALUE 2.2UF
J 0
(1425 350);
DISPLAY 0.978723 (1425 350);
FORCEPROP 1 LAST $LOCATION C47
J 0
(1425 400);
DISPLAY 0.978723 (1425 400);
FORCEPROP 1 LASTPIN (1375 400) $PN 1
J 0
(1385 380);
DISPLAY 0.787234 (1385 380);
FORCEPROP 1 LASTPIN (1375 200) $PN 2
J 0
(1385 180);
DISPLAY 0.787234 (1385 180);
FORCEPROP 2 LAST CDS_LIB pure_quanta
J 0
(1375 300);
PAINT MONO (1375 300);
DISPLAY INVISIBLE (1375 300);
FORCEPROP 2 LAST CDS_LOCATION C47
J 0
(1425 500);
DISPLAY 1.021277 (1425 500);
DISPLAY INVISIBLE (1425 500);
FORCEPROP 2 LAST $SEC 1
J 0
(1425 500);
DISPLAY 0.680851 (1425 500);
PAINT MONO (1425 500);
DISPLAY INVISIBLE (1425 500);
FORCEPROP 2 LAST CDS_SEC 1
J 0
(1425 500);
DISPLAY 1.021277 (1425 500);
DISPLAY INVISIBLE (1425 500);
FORCEPROP 1 LAST PATH I56
J 0
(1425 450);
DISPLAY 0.978723 (1425 450);
PAINT WHITE (1425 450);
DISPLAY INVISIBLE (1425 450);
FORCEADD UNIVERSAL_GND..1
(1375 -75);
FORCEPROP 3 LASTPIN (1375 -25) SIG_NAME GND\g
J 0
(1385 -15);
DISPLAY 0.659574 (1385 -15);
PAINT MONO (1385 -15);
DISPLAY INVISIBLE (1385 -15);
FORCEPROP 2 LAST CDS_LIB logical_power
J 0
(1375 -75);
PAINT MONO (1375 -75);
DISPLAY INVISIBLE (1375 -75);
FORCEPROP 1 LAST HDL_POWER GND
J 1
(1400 -150);
DISPLAY 0.872340 (1400 -150);
PAINT GREEN (1400 -150);
DISPLAY INVISIBLE (1400 -150);
FORCEPROP 1 LAST PATH I57
J 0
(1450 -75);
DISPLAY 0.872340 (1450 -75);
PAINT AQUA (1450 -75);
DISPLAY INVISIBLE (1450 -75);
FORCEADD VCC_CORE..1
(1375 625);
FORCEPROP 3 LASTPIN (1375 575) SIG_NAME P3V3_AUX\g
J 0
(1385 585);
DISPLAY 0.659574 (1385 585);
PAINT MONO (1385 585);
DISPLAY INVISIBLE (1385 585);
FORCEPROP 1 LAST HDL_POWER P3V3_AUX
J 1
(1375 675);
DISPLAY 1.148936 (1375 675);
PAINT GREEN (1375 675);
FORCEPROP 2 LAST CDS_LIB logical_power
J 0
(1375 625);
PAINT MONO (1375 625);
DISPLAY INVISIBLE (1375 625);
FORCEPROP 1 LAST PATH I58
J 0
(1425 650);
DISPLAY 0.872340 (1425 650);
PAINT AQUA (1425 650);
DISPLAY INVISIBLE (1425 650);
FORCEADD Q_CAP..1
(2375 300);
FORCEPROP 1 LAST PART_NUMBER CH6103KEA00
J 0
(2425 150);
DISPLAY 0.978723 (2425 150);
DISPLAY INVISIBLE (2425 150);
FORCEPROP 1 LAST TOLERANCE 10%
J 0
(2425 250);
DISPLAY 0.978723 (2425 250);
FORCEPROP 1 LAST VOLTAGE 16V
J 0
(2425 300);
DISPLAY 0.978723 (2425 300);
FORCEPROP 1 LAST PACK_TYPE C0805
J 0
(2425 100);
DISPLAY 0.978723 (2425 100);
FORCEPROP 1 LAST MATERIAL X6S
J 0
(2425 200);
DISPLAY 0.978723 (2425 200);
FORCEPROP 1 LAST VALUE 10UF
J 0
(2425 350);
DISPLAY 0.978723 (2425 350);
FORCEPROP 1 LAST $LOCATION C48
J 0
(2425 400);
DISPLAY 0.978723 (2425 400);
FORCEPROP 1 LASTPIN (2375 400) $PN 1
J 0
(2385 380);
DISPLAY 0.787234 (2385 380);
FORCEPROP 1 LASTPIN (2375 200) $PN 2
J 0
(2385 180);
DISPLAY 0.787234 (2385 180);
FORCEPROP 2 LAST CDS_LIB pure_quanta
J 0
(2375 300);
PAINT MONO (2375 300);
DISPLAY INVISIBLE (2375 300);
FORCEPROP 2 LAST CDS_LOCATION C48
J 0
(2425 500);
DISPLAY 1.021277 (2425 500);
DISPLAY INVISIBLE (2425 500);
FORCEPROP 2 LAST $SEC 1
J 0
(2425 500);
DISPLAY 0.680851 (2425 500);
PAINT MONO (2425 500);
DISPLAY INVISIBLE (2425 500);
FORCEPROP 2 LAST CDS_SEC 1
J 0
(2425 500);
DISPLAY 1.021277 (2425 500);
DISPLAY INVISIBLE (2425 500);
FORCEPROP 1 LAST PATH I59
J 0
(2425 450);
DISPLAY 0.978723 (2425 450);
PAINT WHITE (2425 450);
DISPLAY INVISIBLE (2425 450);
FORCEADD SCONN288_ADR50017P087CC..1
(-1175 2425);
FORCEPROP 1 LAST PART_NUMBER DFHST8FS460
J 0
(-1620 4435);
DISPLAY 0.723404 (-1620 4435);
PAINT GREEN (-1620 4435);
DISPLAY INVISIBLE (-1620 4435);
FORCEPROP 1 LAST MATERIAL IO
J 0
(-1620 4308);
DISPLAY 0.723404 (-1620 4308);
PAINT GREEN (-1620 4308);
FORCEPROP 2 LAST PART_TYPE SMLF
J 0
(-1625 4600);
DISPLAY 1.021277 (-1625 4600);
FORCEPROP 2 LAST VALUE SCONN288_ADR50017-P087CC
J 0
(-1625 4550);
DISPLAY 1.021277 (-1625 4550);
FORCEPROP 1 LAST $LOCATION J16
J 0
(-1625 4500);
DISPLAY 0.723404 (-1625 4500);
PAINT GREEN (-1625 4500);
FORCEPROP 0 LASTPIN (-1775 1800) $PN 62
J 2
(-1785 1810);
DISPLAY 0.680851 (-1785 1810);
PAINT MONO (-1785 1810);
FORCEPROP 0 LASTPIN (-1775 3850) $PN 66
J 2
(-1785 3860);
DISPLAY 0.680851 (-1785 3860);
PAINT MONO (-1785 3860);
FORCEPROP 0 LASTPIN (-1775 3450) $PN 76
J 2
(-1785 3460);
DISPLAY 0.680851 (-1785 3460);
PAINT MONO (-1785 3460);
FORCEPROP 0 LASTPIN (-1775 3900) $PN 211
J 2
(-1785 3910);
DISPLAY 0.680851 (-1785 3910);
PAINT MONO (-1785 3910);
FORCEPROP 0 LASTPIN (-1775 3500) $PN 221
J 2
(-1785 3510);
DISPLAY 0.680851 (-1785 3510);
PAINT MONO (-1785 3510);
FORCEPROP 0 LASTPIN (-1775 3950) $PN 68
J 2
(-1785 3960);
DISPLAY 0.680851 (-1785 3960);
PAINT MONO (-1785 3960);
FORCEPROP 0 LASTPIN (-1775 3550) $PN 78
J 2
(-1785 3560);
DISPLAY 0.680851 (-1785 3560);
PAINT MONO (-1785 3560);
FORCEPROP 0 LASTPIN (-1775 4000) $PN 213
J 2
(-1785 4010);
DISPLAY 0.680851 (-1785 4010);
PAINT MONO (-1785 4010);
FORCEPROP 0 LASTPIN (-1775 3600) $PN 223
J 2
(-1785 3610);
DISPLAY 0.680851 (-1785 3610);
PAINT MONO (-1785 3610);
FORCEPROP 0 LASTPIN (-1775 4050) $PN 70
J 2
(-1785 4060);
DISPLAY 0.680851 (-1785 4060);
PAINT MONO (-1785 4060);
FORCEPROP 0 LASTPIN (-1775 3650) $PN 80
J 2
(-1785 3660);
DISPLAY 0.680851 (-1785 3660);
PAINT MONO (-1785 3660);
FORCEPROP 0 LASTPIN (-1775 4100) $PN 215
J 2
(-1785 4110);
DISPLAY 0.680851 (-1785 4110);
PAINT MONO (-1785 4110);
FORCEPROP 0 LASTPIN (-1775 3700) $PN 225
J 2
(-1785 3710);
DISPLAY 0.680851 (-1785 3710);
PAINT MONO (-1785 3710);
FORCEPROP 0 LASTPIN (-1775 4150) $PN 72
J 2
(-1785 4160);
DISPLAY 0.680851 (-1785 4160);
PAINT MONO (-1785 4160);
FORCEPROP 0 LASTPIN (-1775 3750) $PN 82
J 2
(-1785 3760);
DISPLAY 0.680851 (-1785 3760);
PAINT MONO (-1785 3760);
FORCEPROP 0 LASTPIN (-1775 2400) $PN 51
J 2
(-1785 2410);
DISPLAY 0.680851 (-1785 2410);
PAINT MONO (-1785 2410);
FORCEPROP 0 LASTPIN (-1775 1950) $PN 96
J 2
(-1785 1960);
DISPLAY 0.680851 (-1785 1960);
PAINT MONO (-1785 1960);
FORCEPROP 0 LASTPIN (-1775 2450) $PN 53
J 2
(-1785 2460);
DISPLAY 0.680851 (-1785 2460);
PAINT MONO (-1785 2460);
FORCEPROP 0 LASTPIN (-1775 2000) $PN 98
J 2
(-1785 2010);
DISPLAY 0.680851 (-1785 2010);
PAINT MONO (-1785 2010);
FORCEPROP 0 LASTPIN (-1775 2500) $PN 196
J 2
(-1785 2510);
DISPLAY 0.680851 (-1785 2510);
PAINT MONO (-1785 2510);
FORCEPROP 0 LASTPIN (-1775 2050) $PN 241
J 2
(-1785 2060);
DISPLAY 0.680851 (-1785 2060);
PAINT MONO (-1785 2060);
FORCEPROP 0 LASTPIN (-1775 2550) $PN 198
J 2
(-1785 2560);
DISPLAY 0.680851 (-1785 2560);
PAINT MONO (-1785 2560);
FORCEPROP 0 LASTPIN (-1775 2100) $PN 243
J 2
(-1785 2110);
DISPLAY 0.680851 (-1785 2110);
PAINT MONO (-1785 2110);
FORCEPROP 0 LASTPIN (-1775 2600) $PN 58
J 2
(-1785 2610);
DISPLAY 0.680851 (-1785 2610);
PAINT MONO (-1785 2610);
FORCEPROP 0 LASTPIN (-1775 2150) $PN 89
J 2
(-1785 2160);
DISPLAY 0.680851 (-1785 2160);
PAINT MONO (-1785 2160);
FORCEPROP 0 LASTPIN (-1775 2650) $PN 60
J 2
(-1785 2660);
DISPLAY 0.680851 (-1785 2660);
PAINT MONO (-1785 2660);
FORCEPROP 0 LASTPIN (-1775 2200) $PN 91
J 2
(-1785 2210);
DISPLAY 0.680851 (-1785 2210);
PAINT MONO (-1785 2210);
FORCEPROP 0 LASTPIN (-1775 2700) $PN 203
J 2
(-1785 2710);
DISPLAY 0.680851 (-1785 2710);
PAINT MONO (-1785 2710);
FORCEPROP 0 LASTPIN (-1775 2250) $PN 234
J 2
(-1785 2260);
DISPLAY 0.680851 (-1785 2260);
PAINT MONO (-1785 2260);
FORCEPROP 0 LASTPIN (-1775 2750) $PN 205
J 2
(-1785 2760);
DISPLAY 0.680851 (-1785 2760);
PAINT MONO (-1785 2760);
FORCEPROP 0 LASTPIN (-1775 2300) $PN 236
J 2
(-1785 2310);
DISPLAY 0.680851 (-1785 2310);
PAINT MONO (-1785 2310);
FORCEPROP 0 LASTPIN (-1775 2850) $PN 218
J 2
(-1785 2860);
DISPLAY 0.680851 (-1785 2860);
PAINT MONO (-1785 2860);
FORCEPROP 0 LASTPIN (-1775 2900) $PN 217
J 2
(-1785 2910);
DISPLAY 0.680851 (-1785 2910);
PAINT MONO (-1785 2910);
FORCEPROP 0 LASTPIN (-1775 3150) $PN 64
J 2
(-1785 3160);
DISPLAY 0.680851 (-1785 3160);
PAINT MONO (-1785 3160);
FORCEPROP 0 LASTPIN (-1775 3000) $PN 84
J 2
(-1785 3010);
DISPLAY 0.680851 (-1785 3010);
PAINT MONO (-1785 3010);
FORCEPROP 0 LASTPIN (-1775 3200) $PN 209
J 2
(-1785 3210);
DISPLAY 0.680851 (-1785 3210);
PAINT MONO (-1785 3210);
FORCEPROP 0 LASTPIN (-1775 3050) $PN 229
J 2
(-1785 3060);
DISPLAY 0.680851 (-1785 3060);
PAINT MONO (-1785 3060);
FORCEPROP 0 LASTPIN (-575 2600) $PN 7
J 0
(-565 2610);
DISPLAY 0.680851 (-565 2610);
PAINT MONO (-565 2610);
FORCEPROP 0 LASTPIN (-575 950) $PN 100
J 0
(-565 960);
DISPLAY 0.680851 (-565 960);
PAINT MONO (-565 960);
FORCEPROP 0 LASTPIN (-575 2650) $PN 9
J 0
(-565 2660);
DISPLAY 0.680851 (-565 2660);
PAINT MONO (-565 2660);
FORCEPROP 0 LASTPIN (-575 1000) $PN 102
J 0
(-565 1010);
DISPLAY 0.680851 (-565 1010);
PAINT MONO (-565 1010);
FORCEPROP 0 LASTPIN (-575 2700) $PN 152
J 0
(-565 2710);
DISPLAY 0.680851 (-565 2710);
PAINT MONO (-565 2710);
FORCEPROP 0 LASTPIN (-575 1050) $PN 245
J 0
(-565 1060);
DISPLAY 0.680851 (-565 1060);
PAINT MONO (-565 1060);
FORCEPROP 0 LASTPIN (-575 2750) $PN 154
J 0
(-565 2760);
DISPLAY 0.680851 (-565 2760);
PAINT MONO (-565 2760);
FORCEPROP 0 LASTPIN (-575 1100) $PN 247
J 0
(-565 1110);
DISPLAY 0.680851 (-565 1110);
PAINT MONO (-565 1110);
FORCEPROP 0 LASTPIN (-575 2800) $PN 14
J 0
(-565 2810);
DISPLAY 0.680851 (-565 2810);
PAINT MONO (-565 2810);
FORCEPROP 0 LASTPIN (-575 1150) $PN 107
J 0
(-565 1160);
DISPLAY 0.680851 (-565 1160);
PAINT MONO (-565 1160);
FORCEPROP 0 LASTPIN (-575 2850) $PN 16
J 0
(-565 2860);
DISPLAY 0.680851 (-565 2860);
PAINT MONO (-565 2860);
FORCEPROP 0 LASTPIN (-575 1200) $PN 109
J 0
(-565 1210);
DISPLAY 0.680851 (-565 1210);
PAINT MONO (-565 1210);
FORCEPROP 0 LASTPIN (-575 2900) $PN 159
J 0
(-565 2910);
DISPLAY 0.680851 (-565 2910);
PAINT MONO (-565 2910);
FORCEPROP 0 LASTPIN (-575 1250) $PN 252
J 0
(-565 1260);
DISPLAY 0.680851 (-565 1260);
PAINT MONO (-565 1260);
FORCEPROP 0 LASTPIN (-575 2950) $PN 161
J 0
(-565 2960);
DISPLAY 0.680851 (-565 2960);
PAINT MONO (-565 2960);
FORCEPROP 0 LASTPIN (-575 1300) $PN 254
J 0
(-565 1310);
DISPLAY 0.680851 (-565 1310);
PAINT MONO (-565 1310);
FORCEPROP 0 LASTPIN (-575 3000) $PN 18
J 0
(-565 3010);
DISPLAY 0.680851 (-565 3010);
PAINT MONO (-565 3010);
FORCEPROP 0 LASTPIN (-575 1350) $PN 111
J 0
(-565 1360);
DISPLAY 0.680851 (-565 1360);
PAINT MONO (-565 1360);
FORCEPROP 0 LASTPIN (-575 3050) $PN 20
J 0
(-565 3060);
DISPLAY 0.680851 (-565 3060);
PAINT MONO (-565 3060);
FORCEPROP 0 LASTPIN (-575 1400) $PN 113
J 0
(-565 1410);
DISPLAY 0.680851 (-565 1410);
PAINT MONO (-565 1410);
FORCEPROP 0 LASTPIN (-575 3100) $PN 163
J 0
(-565 3110);
DISPLAY 0.680851 (-565 3110);
PAINT MONO (-565 3110);
FORCEPROP 0 LASTPIN (-575 1450) $PN 256
J 0
(-565 1460);
DISPLAY 0.680851 (-565 1460);
PAINT MONO (-565 1460);
FORCEPROP 0 LASTPIN (-575 3150) $PN 165
J 0
(-565 3160);
DISPLAY 0.680851 (-565 3160);
PAINT MONO (-565 3160);
FORCEPROP 0 LASTPIN (-575 1500) $PN 258
J 0
(-565 1510);
DISPLAY 0.680851 (-565 1510);
PAINT MONO (-565 1510);
FORCEPROP 0 LASTPIN (-575 3200) $PN 25
J 0
(-565 3210);
DISPLAY 0.680851 (-565 3210);
PAINT MONO (-565 3210);
FORCEPROP 0 LASTPIN (-575 1550) $PN 118
J 0
(-565 1560);
DISPLAY 0.680851 (-565 1560);
PAINT MONO (-565 1560);
FORCEPROP 0 LASTPIN (-575 3250) $PN 27
J 0
(-565 3260);
DISPLAY 0.680851 (-565 3260);
PAINT MONO (-565 3260);
FORCEPROP 0 LASTPIN (-575 1600) $PN 120
J 0
(-565 1610);
DISPLAY 0.680851 (-565 1610);
PAINT MONO (-565 1610);
FORCEPROP 0 LASTPIN (-575 3300) $PN 170
J 0
(-565 3310);
DISPLAY 0.680851 (-565 3310);
PAINT MONO (-565 3310);
FORCEPROP 0 LASTPIN (-575 1650) $PN 263
J 0
(-565 1660);
DISPLAY 0.680851 (-565 1660);
PAINT MONO (-565 1660);
FORCEPROP 0 LASTPIN (-575 3350) $PN 172
J 0
(-565 3360);
DISPLAY 0.680851 (-565 3360);
PAINT MONO (-565 3360);
FORCEPROP 0 LASTPIN (-575 1700) $PN 265
J 0
(-565 1710);
DISPLAY 0.680851 (-565 1710);
PAINT MONO (-565 1710);
FORCEPROP 0 LASTPIN (-575 3400) $PN 29
J 0
(-565 3410);
DISPLAY 0.680851 (-565 3410);
PAINT MONO (-565 3410);
FORCEPROP 0 LASTPIN (-575 1750) $PN 122
J 0
(-565 1760);
DISPLAY 0.680851 (-565 1760);
PAINT MONO (-565 1760);
FORCEPROP 0 LASTPIN (-575 3450) $PN 31
J 0
(-565 3460);
DISPLAY 0.680851 (-565 3460);
PAINT MONO (-565 3460);
FORCEPROP 0 LASTPIN (-575 1800) $PN 124
J 0
(-565 1810);
DISPLAY 0.680851 (-565 1810);
PAINT MONO (-565 1810);
FORCEPROP 0 LASTPIN (-575 3500) $PN 174
J 0
(-565 3510);
DISPLAY 0.680851 (-565 3510);
PAINT MONO (-565 3510);
FORCEPROP 0 LASTPIN (-575 1850) $PN 267
J 0
(-565 1860);
DISPLAY 0.680851 (-565 1860);
PAINT MONO (-565 1860);
FORCEPROP 0 LASTPIN (-575 3550) $PN 176
J 0
(-565 3560);
DISPLAY 0.680851 (-565 3560);
PAINT MONO (-565 3560);
FORCEPROP 0 LASTPIN (-575 1900) $PN 269
J 0
(-565 1910);
DISPLAY 0.680851 (-565 1910);
PAINT MONO (-565 1910);
FORCEPROP 0 LASTPIN (-575 3600) $PN 36
J 0
(-565 3610);
DISPLAY 0.680851 (-565 3610);
PAINT MONO (-565 3610);
FORCEPROP 0 LASTPIN (-575 1950) $PN 129
J 0
(-565 1960);
DISPLAY 0.680851 (-565 1960);
PAINT MONO (-565 1960);
FORCEPROP 0 LASTPIN (-575 3650) $PN 38
J 0
(-565 3660);
DISPLAY 0.680851 (-565 3660);
PAINT MONO (-565 3660);
FORCEPROP 0 LASTPIN (-575 2000) $PN 131
J 0
(-565 2010);
DISPLAY 0.680851 (-565 2010);
PAINT MONO (-565 2010);
FORCEPROP 0 LASTPIN (-575 3700) $PN 181
J 0
(-565 3710);
DISPLAY 0.680851 (-565 3710);
PAINT MONO (-565 3710);
FORCEPROP 0 LASTPIN (-575 2050) $PN 274
J 0
(-565 2060);
DISPLAY 0.680851 (-565 2060);
PAINT MONO (-565 2060);
FORCEPROP 0 LASTPIN (-575 3750) $PN 183
J 0
(-565 3760);
DISPLAY 0.680851 (-565 3760);
PAINT MONO (-565 3760);
FORCEPROP 0 LASTPIN (-575 2100) $PN 276
J 0
(-565 2110);
DISPLAY 0.680851 (-565 2110);
PAINT MONO (-565 2110);
FORCEPROP 0 LASTPIN (-575 3800) $PN 40
J 0
(-565 3810);
DISPLAY 0.680851 (-565 3810);
PAINT MONO (-565 3810);
FORCEPROP 0 LASTPIN (-575 2150) $PN 133
J 0
(-565 2160);
DISPLAY 0.680851 (-565 2160);
PAINT MONO (-565 2160);
FORCEPROP 0 LASTPIN (-575 3850) $PN 42
J 0
(-565 3860);
DISPLAY 0.680851 (-565 3860);
PAINT MONO (-565 3860);
FORCEPROP 0 LASTPIN (-575 2200) $PN 135
J 0
(-565 2210);
DISPLAY 0.680851 (-565 2210);
PAINT MONO (-565 2210);
FORCEPROP 0 LASTPIN (-575 3900) $PN 185
J 0
(-565 3910);
DISPLAY 0.680851 (-565 3910);
PAINT MONO (-565 3910);
FORCEPROP 0 LASTPIN (-575 2250) $PN 278
J 0
(-565 2260);
DISPLAY 0.680851 (-565 2260);
PAINT MONO (-565 2260);
FORCEPROP 0 LASTPIN (-575 3950) $PN 187
J 0
(-565 3960);
DISPLAY 0.680851 (-565 3960);
PAINT MONO (-565 3960);
FORCEPROP 0 LASTPIN (-575 2300) $PN 280
J 0
(-565 2310);
DISPLAY 0.680851 (-565 2310);
PAINT MONO (-565 2310);
FORCEPROP 0 LASTPIN (-575 4000) $PN 47
J 0
(-565 4010);
DISPLAY 0.680851 (-565 4010);
PAINT MONO (-565 4010);
FORCEPROP 0 LASTPIN (-575 2350) $PN 140
J 0
(-565 2360);
DISPLAY 0.680851 (-565 2360);
PAINT MONO (-565 2360);
FORCEPROP 0 LASTPIN (-575 4050) $PN 49
J 0
(-565 4060);
DISPLAY 0.680851 (-565 4060);
PAINT MONO (-565 4060);
FORCEPROP 0 LASTPIN (-575 2400) $PN 142
J 0
(-565 2410);
DISPLAY 0.680851 (-565 2410);
PAINT MONO (-565 2410);
FORCEPROP 0 LASTPIN (-575 4100) $PN 192
J 0
(-565 4110);
DISPLAY 0.680851 (-565 4110);
PAINT MONO (-565 4110);
FORCEPROP 0 LASTPIN (-575 2450) $PN 285
J 0
(-565 2460);
DISPLAY 0.680851 (-565 2460);
PAINT MONO (-565 2460);
FORCEPROP 0 LASTPIN (-575 4150) $PN 194
J 0
(-565 4160);
DISPLAY 0.680851 (-565 4160);
PAINT MONO (-565 4160);
FORCEPROP 0 LASTPIN (-575 2500) $PN 287
J 0
(-565 2510);
DISPLAY 0.680851 (-565 2510);
PAINT MONO (-565 2510);
FORCEPROP 0 LASTPIN (-1775 1650) $PN 148
J 2
(-1785 1660);
DISPLAY 0.680851 (-1785 1660);
PAINT MONO (-1785 1660);
FORCEPROP 0 LASTPIN (-1775 1550) $PN 4
J 2
(-1785 1560);
DISPLAY 0.680851 (-1785 1560);
PAINT MONO (-1785 1560);
FORCEPROP 0 LASTPIN (-1775 1600) $PN 5
J 2
(-1785 1610);
DISPLAY 0.680851 (-1785 1610);
PAINT MONO (-1785 1610);
FORCEPROP 0 LASTPIN (-1775 750) $PN 86
J 2
(-1785 760);
DISPLAY 0.680851 (-1785 760);
PAINT MONO (-1785 760);
FORCEPROP 0 LASTPIN (-1775 700) $PN 87
J 2
(-1785 710);
DISPLAY 0.680851 (-1785 710);
PAINT MONO (-1785 710);
FORCEPROP 0 LASTPIN (-1775 3350) $PN 74
J 2
(-1785 3360);
DISPLAY 0.680851 (-1785 3360);
PAINT MONO (-1785 3360);
FORCEPROP 0 LASTPIN (-1775 3300) $PN 227
J 2
(-1785 3310);
DISPLAY 0.680851 (-1785 3310);
PAINT MONO (-1785 3310);
FORCEPROP 0 LASTPIN (-1775 1300) $PN 147
J 2
(-1785 1310);
DISPLAY 0.680851 (-1785 1310);
PAINT MONO (-1785 1310);
FORCEPROP 0 LASTPIN (-1775 1850) $PN 207
J 2
(-1785 1860);
DISPLAY 0.680851 (-1785 1860);
PAINT MONO (-1785 1860);
FORCEPROP 0 LASTPIN (-1775 900) $PN 2
J 2
(-1785 910);
DISPLAY 0.680851 (-1785 910);
PAINT MONO (-1785 910);
FORCEPROP 0 LASTPIN (-1775 950) $PN 144
J 2
(-1785 960);
DISPLAY 0.680851 (-1785 960);
PAINT MONO (-1785 960);
FORCEPROP 0 LASTPIN (-1775 1000) $PN 149
J 2
(-1785 1010);
DISPLAY 0.680851 (-1785 1010);
PAINT MONO (-1785 1010);
FORCEPROP 0 LASTPIN (-1775 1050) $PN 150
J 2
(-1785 1060);
DISPLAY 0.680851 (-1785 1060);
PAINT MONO (-1785 1060);
FORCEPROP 0 LASTPIN (-1775 1100) $PN 220
J 2
(-1785 1110);
DISPLAY 0.680851 (-1785 1110);
PAINT MONO (-1785 1110);
FORCEPROP 0 LASTPIN (-1775 1150) $PN 231
J 2
(-1785 1160);
DISPLAY 0.680851 (-1785 1160);
PAINT MONO (-1785 1160);
FORCEPROP 0 LASTPIN (-1775 1200) $PN 232
J 2
(-1785 1210);
DISPLAY 0.680851 (-1785 1210);
PAINT MONO (-1785 1210);
FORCEPROP 0 LASTPIN (-1775 1700) $PN 3
J 2
(-1785 1710);
DISPLAY 0.680851 (-1785 1710);
PAINT MONO (-1785 1710);
FORCEPROP 2 LAST CDS_LIB pure_quanta
J 0
(-1175 2425);
DISPLAY INVISIBLE (-1175 2425);
FORCEPROP 1 LAST CDS_LMAN_SYM_OUTLINE -450,1875,450,-1875
J 0
(-1175 2425);
DISPLAY 0.468085 (-1175 2425);
PAINT GREEN (-1175 2425);
DISPLAY INVISIBLE (-1175 2425);
FORCEPROP 1 LAST NEEDS_NO_SIZE TRUE
J 0
(-1175 2425);
DISPLAY 0.723404 (-1175 2425);
PAINT GREEN (-1175 2425);
DISPLAY INVISIBLE (-1175 2425);
FORCEPROP 2 LAST CDS_LOCATION J16
J 0
(-1625 4650);
DISPLAY 1.021277 (-1625 4650);
DISPLAY INVISIBLE (-1625 4650);
FORCEPROP 0 LAST $SEC 1
J 0
(-1625 4650);
DISPLAY 0.680851 (-1625 4650);
PAINT MONO (-1625 4650);
DISPLAY INVISIBLE (-1625 4650);
FORCEPROP 2 LAST CDS_SEC 1
J 0
(-1625 4650);
DISPLAY 1.021277 (-1625 4650);
DISPLAY INVISIBLE (-1625 4650);
FORCEPROP 1 LAST PATH I6
J 0
(-1175 2425);
DISPLAY 0.723404 (-1175 2425);
PAINT GREEN (-1175 2425);
DISPLAY INVISIBLE (-1175 2425);
FORCEADD VCC_CORE..1
(2375 625);
FORCEPROP 3 LASTPIN (2375 575) SIG_NAME P12V_S3_AUX_CPU0_NVDIMM\g
J 0
(2385 585);
DISPLAY 0.659574 (2385 585);
PAINT MONO (2385 585);
DISPLAY INVISIBLE (2385 585);
FORCEPROP 1 LAST HDL_POWER P12V_S3_AUX_CPU0_NVDIMM
J 1
(2375 675);
DISPLAY 1.148936 (2375 675);
PAINT GREEN (2375 675);
FORCEPROP 2 LAST CDS_LIB logical_power
J 0
(2375 625);
PAINT MONO (2375 625);
DISPLAY INVISIBLE (2375 625);
FORCEPROP 1 LAST PATH I60
J 0
(2425 650);
DISPLAY 0.872340 (2425 650);
PAINT AQUA (2425 650);
DISPLAY INVISIBLE (2425 650);
FORCEADD UNIVERSAL_GND..1
(3000 -75);
FORCEPROP 3 LASTPIN (3000 -25) SIG_NAME GND\g
J 0
(3010 -15);
DISPLAY 0.659574 (3010 -15);
PAINT MONO (3010 -15);
DISPLAY INVISIBLE (3010 -15);
FORCEPROP 2 LAST CDS_LIB logical_power
J 0
(3000 -75);
PAINT MONO (3000 -75);
DISPLAY INVISIBLE (3000 -75);
FORCEPROP 1 LAST HDL_POWER GND
J 1
(3025 -150);
DISPLAY 0.872340 (3025 -150);
PAINT GREEN (3025 -150);
DISPLAY INVISIBLE (3025 -150);
FORCEPROP 1 LAST PATH I61
J 0
(3075 -75);
DISPLAY 0.872340 (3075 -75);
PAINT AQUA (3075 -75);
DISPLAY INVISIBLE (3075 -75);
FORCEADD Q_CAP..1
(3000 300);
FORCEPROP 1 LAST PART_NUMBER CH6103KEA00
J 0
(3050 150);
DISPLAY 0.978723 (3050 150);
DISPLAY INVISIBLE (3050 150);
FORCEPROP 1 LAST PACK_TYPE C0805
J 0
(3050 100);
DISPLAY 0.978723 (3050 100);
FORCEPROP 1 LAST VALUE 10UF
J 0
(3050 350);
DISPLAY 0.978723 (3050 350);
FORCEPROP 1 LAST VOLTAGE 16V
J 0
(3050 300);
DISPLAY 0.978723 (3050 300);
FORCEPROP 1 LAST TOLERANCE 10%
J 0
(3050 250);
DISPLAY 0.978723 (3050 250);
FORCEPROP 1 LAST MATERIAL X6S
J 0
(3050 200);
DISPLAY 0.978723 (3050 200);
FORCEPROP 1 LAST $LOCATION C49
J 0
(3050 400);
DISPLAY 0.978723 (3050 400);
FORCEPROP 1 LASTPIN (3000 400) $PN 1
J 0
(3010 380);
DISPLAY 0.787234 (3010 380);
FORCEPROP 1 LASTPIN (3000 200) $PN 2
J 0
(3010 180);
DISPLAY 0.787234 (3010 180);
FORCEPROP 2 LAST CDS_LIB pure_quanta
J 0
(3000 300);
PAINT MONO (3000 300);
DISPLAY INVISIBLE (3000 300);
FORCEPROP 2 LAST CDS_LOCATION C49
J 0
(3050 500);
DISPLAY 1.021277 (3050 500);
DISPLAY INVISIBLE (3050 500);
FORCEPROP 2 LAST $SEC 1
J 0
(3050 500);
DISPLAY 0.680851 (3050 500);
PAINT MONO (3050 500);
DISPLAY INVISIBLE (3050 500);
FORCEPROP 2 LAST CDS_SEC 1
J 0
(3050 500);
DISPLAY 1.021277 (3050 500);
DISPLAY INVISIBLE (3050 500);
FORCEPROP 1 LAST PATH I62
J 0
(3050 450);
DISPLAY 0.978723 (3050 450);
PAINT WHITE (3050 450);
DISPLAY INVISIBLE (3050 450);
FORCEADD UNIVERSAL_GND..1
(4075 475);
FORCEPROP 3 LASTPIN (4075 525) SIG_NAME GND\g
J 0
(4085 535);
DISPLAY 0.659574 (4085 535);
PAINT MONO (4085 535);
DISPLAY INVISIBLE (4085 535);
FORCEPROP 2 LAST CDS_LIB logical_power
J 0
(4075 475);
PAINT MONO (4075 475);
DISPLAY INVISIBLE (4075 475);
FORCEPROP 1 LAST HDL_POWER GND
J 1
(4100 400);
DISPLAY 0.872340 (4100 400);
PAINT GREEN (4100 400);
DISPLAY INVISIBLE (4100 400);
FORCEPROP 1 LAST PATH I63
J 0
(4150 475);
DISPLAY 0.872340 (4150 475);
PAINT AQUA (4150 475);
DISPLAY INVISIBLE (4150 475);
FORCEADD SCONN288_ADR50017P087CC..3
(4925 2550);
FORCEPROP 1 LAST PART_NUMBER DFHST8FS460
J 0
(4470 4474);
DISPLAY 0.723404 (4470 4474);
PAINT GREEN (4470 4474);
DISPLAY INVISIBLE (4470 4474);
FORCEPROP 1 LAST MATERIAL IO
J 0
(4470 4347);
DISPLAY 0.723404 (4470 4347);
PAINT GREEN (4470 4347);
FORCEPROP 2 LAST VALUE SCONN288_ADR50017-P087CC
J 0
(4475 4575);
DISPLAY 1.021277 (4475 4575);
FORCEPROP 2 LAST PART_TYPE SMLF
J 0
(4475 4625);
DISPLAY 1.021277 (4475 4625);
FORCEPROP 1 LAST $LOCATION J16
J 0
(4475 4525);
DISPLAY 0.723404 (4475 4525);
PAINT GREEN (4475 4525);
FORCEPROP 0 LASTPIN (5525 925) $PN G1
J 0
(5535 935);
DISPLAY 0.680851 (5535 935);
PAINT MONO (5535 935);
FORCEPROP 0 LASTPIN (5525 875) $PN G2
J 0
(5535 885);
DISPLAY 0.680851 (5535 885);
PAINT MONO (5535 885);
FORCEPROP 0 LASTPIN (5525 825) $PN G3
J 0
(5535 835);
DISPLAY 0.680851 (5535 835);
PAINT MONO (5535 835);
FORCEPROP 0 LASTPIN (4325 4075) $PN 1
J 2
(4315 4085);
DISPLAY 0.680851 (4315 4085);
PAINT MONO (4315 4085);
FORCEPROP 0 LASTPIN (4325 4125) $PN 145
J 2
(4315 4135);
DISPLAY 0.680851 (4315 4135);
PAINT MONO (4315 4135);
FORCEPROP 0 LASTPIN (4325 4175) $PN 146
J 2
(4315 4185);
DISPLAY 0.680851 (4315 4185);
PAINT MONO (4315 4185);
FORCEPROP 0 LASTPIN (5525 1025) $PN 6
J 0
(5535 1035);
DISPLAY 0.680851 (5535 1035);
PAINT MONO (5535 1035);
FORCEPROP 0 LASTPIN (5525 1075) $PN 8
J 0
(5535 1085);
DISPLAY 0.680851 (5535 1085);
PAINT MONO (5535 1085);
FORCEPROP 0 LASTPIN (5525 1125) $PN 10
J 0
(5535 1135);
DISPLAY 0.680851 (5535 1135);
PAINT MONO (5535 1135);
FORCEPROP 0 LASTPIN (5525 1175) $PN 13
J 0
(5535 1185);
DISPLAY 0.680851 (5535 1185);
PAINT MONO (5535 1185);
FORCEPROP 0 LASTPIN (5525 1225) $PN 15
J 0
(5535 1235);
DISPLAY 0.680851 (5535 1235);
PAINT MONO (5535 1235);
FORCEPROP 0 LASTPIN (5525 1275) $PN 17
J 0
(5535 1285);
DISPLAY 0.680851 (5535 1285);
PAINT MONO (5535 1285);
FORCEPROP 0 LASTPIN (5525 1325) $PN 19
J 0
(5535 1335);
DISPLAY 0.680851 (5535 1335);
PAINT MONO (5535 1335);
FORCEPROP 0 LASTPIN (5525 1375) $PN 21
J 0
(5535 1385);
DISPLAY 0.680851 (5535 1385);
PAINT MONO (5535 1385);
FORCEPROP 0 LASTPIN (5525 1425) $PN 24
J 0
(5535 1435);
DISPLAY 0.680851 (5535 1435);
PAINT MONO (5535 1435);
FORCEPROP 0 LASTPIN (5525 1475) $PN 26
J 0
(5535 1485);
DISPLAY 0.680851 (5535 1485);
PAINT MONO (5535 1485);
FORCEPROP 0 LASTPIN (5525 1525) $PN 28
J 0
(5535 1535);
DISPLAY 0.680851 (5535 1535);
PAINT MONO (5535 1535);
FORCEPROP 0 LASTPIN (5525 1575) $PN 30
J 0
(5535 1585);
DISPLAY 0.680851 (5535 1585);
PAINT MONO (5535 1585);
FORCEPROP 0 LASTPIN (5525 1625) $PN 32
J 0
(5535 1635);
DISPLAY 0.680851 (5535 1635);
PAINT MONO (5535 1635);
FORCEPROP 0 LASTPIN (5525 1675) $PN 35
J 0
(5535 1685);
DISPLAY 0.680851 (5535 1685);
PAINT MONO (5535 1685);
FORCEPROP 0 LASTPIN (5525 1725) $PN 37
J 0
(5535 1735);
DISPLAY 0.680851 (5535 1735);
PAINT MONO (5535 1735);
FORCEPROP 0 LASTPIN (5525 1775) $PN 39
J 0
(5535 1785);
DISPLAY 0.680851 (5535 1785);
PAINT MONO (5535 1785);
FORCEPROP 0 LASTPIN (5525 1825) $PN 41
J 0
(5535 1835);
DISPLAY 0.680851 (5535 1835);
PAINT MONO (5535 1835);
FORCEPROP 0 LASTPIN (5525 1875) $PN 43
J 0
(5535 1885);
DISPLAY 0.680851 (5535 1885);
PAINT MONO (5535 1885);
FORCEPROP 0 LASTPIN (5525 1925) $PN 46
J 0
(5535 1935);
DISPLAY 0.680851 (5535 1935);
PAINT MONO (5535 1935);
FORCEPROP 0 LASTPIN (5525 1975) $PN 48
J 0
(5535 1985);
DISPLAY 0.680851 (5535 1985);
PAINT MONO (5535 1985);
FORCEPROP 0 LASTPIN (5525 2025) $PN 50
J 0
(5535 2035);
DISPLAY 0.680851 (5535 2035);
PAINT MONO (5535 2035);
FORCEPROP 0 LASTPIN (5525 2075) $PN 52
J 0
(5535 2085);
DISPLAY 0.680851 (5535 2085);
PAINT MONO (5535 2085);
FORCEPROP 0 LASTPIN (5525 2125) $PN 54
J 0
(5535 2135);
DISPLAY 0.680851 (5535 2135);
PAINT MONO (5535 2135);
FORCEPROP 0 LASTPIN (5525 2175) $PN 57
J 0
(5535 2185);
DISPLAY 0.680851 (5535 2185);
PAINT MONO (5535 2185);
FORCEPROP 0 LASTPIN (5525 2225) $PN 59
J 0
(5535 2235);
DISPLAY 0.680851 (5535 2235);
PAINT MONO (5535 2235);
FORCEPROP 0 LASTPIN (5525 2275) $PN 61
J 0
(5535 2285);
DISPLAY 0.680851 (5535 2285);
PAINT MONO (5535 2285);
FORCEPROP 0 LASTPIN (5525 2325) $PN 63
J 0
(5535 2335);
DISPLAY 0.680851 (5535 2335);
PAINT MONO (5535 2335);
FORCEPROP 0 LASTPIN (5525 2375) $PN 65
J 0
(5535 2385);
DISPLAY 0.680851 (5535 2385);
PAINT MONO (5535 2385);
FORCEPROP 0 LASTPIN (5525 2425) $PN 67
J 0
(5535 2435);
DISPLAY 0.680851 (5535 2435);
PAINT MONO (5535 2435);
FORCEPROP 0 LASTPIN (5525 2475) $PN 69
J 0
(5535 2485);
DISPLAY 0.680851 (5535 2485);
PAINT MONO (5535 2485);
FORCEPROP 0 LASTPIN (5525 2525) $PN 71
J 0
(5535 2535);
DISPLAY 0.680851 (5535 2535);
PAINT MONO (5535 2535);
FORCEPROP 0 LASTPIN (5525 2575) $PN 73
J 0
(5535 2585);
DISPLAY 0.680851 (5535 2585);
PAINT MONO (5535 2585);
FORCEPROP 0 LASTPIN (5525 2625) $PN 75
J 0
(5535 2635);
DISPLAY 0.680851 (5535 2635);
PAINT MONO (5535 2635);
FORCEPROP 0 LASTPIN (5525 2675) $PN 77
J 0
(5535 2685);
DISPLAY 0.680851 (5535 2685);
PAINT MONO (5535 2685);
FORCEPROP 0 LASTPIN (5525 2725) $PN 79
J 0
(5535 2735);
DISPLAY 0.680851 (5535 2735);
PAINT MONO (5535 2735);
FORCEPROP 0 LASTPIN (5525 2775) $PN 81
J 0
(5535 2785);
DISPLAY 0.680851 (5535 2785);
PAINT MONO (5535 2785);
FORCEPROP 0 LASTPIN (5525 2825) $PN 83
J 0
(5535 2835);
DISPLAY 0.680851 (5535 2835);
PAINT MONO (5535 2835);
FORCEPROP 0 LASTPIN (5525 2875) $PN 85
J 0
(5535 2885);
DISPLAY 0.680851 (5535 2885);
PAINT MONO (5535 2885);
FORCEPROP 0 LASTPIN (5525 2925) $PN 88
J 0
(5535 2935);
DISPLAY 0.680851 (5535 2935);
PAINT MONO (5535 2935);
FORCEPROP 0 LASTPIN (5525 2975) $PN 90
J 0
(5535 2985);
DISPLAY 0.680851 (5535 2985);
PAINT MONO (5535 2985);
FORCEPROP 0 LASTPIN (5525 3025) $PN 92
J 0
(5535 3035);
DISPLAY 0.680851 (5535 3035);
PAINT MONO (5535 3035);
FORCEPROP 0 LASTPIN (5525 3075) $PN 95
J 0
(5535 3085);
DISPLAY 0.680851 (5535 3085);
PAINT MONO (5535 3085);
FORCEPROP 0 LASTPIN (5525 3125) $PN 97
J 0
(5535 3135);
DISPLAY 0.680851 (5535 3135);
PAINT MONO (5535 3135);
FORCEPROP 0 LASTPIN (5525 3175) $PN 99
J 0
(5535 3185);
DISPLAY 0.680851 (5535 3185);
PAINT MONO (5535 3185);
FORCEPROP 0 LASTPIN (5525 3225) $PN 101
J 0
(5535 3235);
DISPLAY 0.680851 (5535 3235);
PAINT MONO (5535 3235);
FORCEPROP 0 LASTPIN (5525 3275) $PN 103
J 0
(5535 3285);
DISPLAY 0.680851 (5535 3285);
PAINT MONO (5535 3285);
FORCEPROP 0 LASTPIN (5525 3325) $PN 106
J 0
(5535 3335);
DISPLAY 0.680851 (5535 3335);
PAINT MONO (5535 3335);
FORCEPROP 0 LASTPIN (5525 3375) $PN 108
J 0
(5535 3385);
DISPLAY 0.680851 (5535 3385);
PAINT MONO (5535 3385);
FORCEPROP 0 LASTPIN (5525 3425) $PN 110
J 0
(5535 3435);
DISPLAY 0.680851 (5535 3435);
PAINT MONO (5535 3435);
FORCEPROP 0 LASTPIN (5525 3475) $PN 112
J 0
(5535 3485);
DISPLAY 0.680851 (5535 3485);
PAINT MONO (5535 3485);
FORCEPROP 0 LASTPIN (5525 3525) $PN 114
J 0
(5535 3535);
DISPLAY 0.680851 (5535 3535);
PAINT MONO (5535 3535);
FORCEPROP 0 LASTPIN (5525 3575) $PN 117
J 0
(5535 3585);
DISPLAY 0.680851 (5535 3585);
PAINT MONO (5535 3585);
FORCEPROP 0 LASTPIN (5525 3625) $PN 119
J 0
(5535 3635);
DISPLAY 0.680851 (5535 3635);
PAINT MONO (5535 3635);
FORCEPROP 0 LASTPIN (5525 3675) $PN 121
J 0
(5535 3685);
DISPLAY 0.680851 (5535 3685);
PAINT MONO (5535 3685);
FORCEPROP 0 LASTPIN (5525 3725) $PN 123
J 0
(5535 3735);
DISPLAY 0.680851 (5535 3735);
PAINT MONO (5535 3735);
FORCEPROP 0 LASTPIN (5525 3775) $PN 125
J 0
(5535 3785);
DISPLAY 0.680851 (5535 3785);
PAINT MONO (5535 3785);
FORCEPROP 0 LASTPIN (5525 3825) $PN 128
J 0
(5535 3835);
DISPLAY 0.680851 (5535 3835);
PAINT MONO (5535 3835);
FORCEPROP 0 LASTPIN (5525 3875) $PN 130
J 0
(5535 3885);
DISPLAY 0.680851 (5535 3885);
PAINT MONO (5535 3885);
FORCEPROP 0 LASTPIN (5525 3925) $PN 132
J 0
(5535 3935);
DISPLAY 0.680851 (5535 3935);
PAINT MONO (5535 3935);
FORCEPROP 0 LASTPIN (5525 3975) $PN 134
J 0
(5535 3985);
DISPLAY 0.680851 (5535 3985);
PAINT MONO (5535 3985);
FORCEPROP 0 LASTPIN (5525 4025) $PN 136
J 0
(5535 4035);
DISPLAY 0.680851 (5535 4035);
PAINT MONO (5535 4035);
FORCEPROP 0 LASTPIN (5525 4075) $PN 139
J 0
(5535 4085);
DISPLAY 0.680851 (5535 4085);
PAINT MONO (5535 4085);
FORCEPROP 0 LASTPIN (5525 4125) $PN 141
J 0
(5535 4135);
DISPLAY 0.680851 (5535 4135);
PAINT MONO (5535 4135);
FORCEPROP 0 LASTPIN (5525 4175) $PN 143
J 0
(5535 4185);
DISPLAY 0.680851 (5535 4185);
PAINT MONO (5535 4185);
FORCEPROP 0 LASTPIN (4325 925) $PN 151
J 2
(4315 935);
DISPLAY 0.680851 (4315 935);
PAINT MONO (4315 935);
FORCEPROP 0 LASTPIN (4325 975) $PN 153
J 2
(4315 985);
DISPLAY 0.680851 (4315 985);
PAINT MONO (4315 985);
FORCEPROP 0 LASTPIN (4325 1025) $PN 155
J 2
(4315 1035);
DISPLAY 0.680851 (4315 1035);
PAINT MONO (4315 1035);
FORCEPROP 0 LASTPIN (4325 1075) $PN 158
J 2
(4315 1085);
DISPLAY 0.680851 (4315 1085);
PAINT MONO (4315 1085);
FORCEPROP 0 LASTPIN (4325 1125) $PN 160
J 2
(4315 1135);
DISPLAY 0.680851 (4315 1135);
PAINT MONO (4315 1135);
FORCEPROP 0 LASTPIN (4325 1175) $PN 162
J 2
(4315 1185);
DISPLAY 0.680851 (4315 1185);
PAINT MONO (4315 1185);
FORCEPROP 0 LASTPIN (4325 1225) $PN 164
J 2
(4315 1235);
DISPLAY 0.680851 (4315 1235);
PAINT MONO (4315 1235);
FORCEPROP 0 LASTPIN (4325 1275) $PN 166
J 2
(4315 1285);
DISPLAY 0.680851 (4315 1285);
PAINT MONO (4315 1285);
FORCEPROP 0 LASTPIN (4325 1325) $PN 169
J 2
(4315 1335);
DISPLAY 0.680851 (4315 1335);
PAINT MONO (4315 1335);
FORCEPROP 0 LASTPIN (4325 1375) $PN 171
J 2
(4315 1385);
DISPLAY 0.680851 (4315 1385);
PAINT MONO (4315 1385);
FORCEPROP 0 LASTPIN (4325 1425) $PN 173
J 2
(4315 1435);
DISPLAY 0.680851 (4315 1435);
PAINT MONO (4315 1435);
FORCEPROP 0 LASTPIN (4325 1475) $PN 175
J 2
(4315 1485);
DISPLAY 0.680851 (4315 1485);
PAINT MONO (4315 1485);
FORCEPROP 0 LASTPIN (4325 1525) $PN 177
J 2
(4315 1535);
DISPLAY 0.680851 (4315 1535);
PAINT MONO (4315 1535);
FORCEPROP 0 LASTPIN (4325 1575) $PN 180
J 2
(4315 1585);
DISPLAY 0.680851 (4315 1585);
PAINT MONO (4315 1585);
FORCEPROP 0 LASTPIN (4325 1625) $PN 182
J 2
(4315 1635);
DISPLAY 0.680851 (4315 1635);
PAINT MONO (4315 1635);
FORCEPROP 0 LASTPIN (4325 1675) $PN 184
J 2
(4315 1685);
DISPLAY 0.680851 (4315 1685);
PAINT MONO (4315 1685);
FORCEPROP 0 LASTPIN (4325 1725) $PN 186
J 2
(4315 1735);
DISPLAY 0.680851 (4315 1735);
PAINT MONO (4315 1735);
FORCEPROP 0 LASTPIN (4325 1775) $PN 188
J 2
(4315 1785);
DISPLAY 0.680851 (4315 1785);
PAINT MONO (4315 1785);
FORCEPROP 0 LASTPIN (4325 1825) $PN 191
J 2
(4315 1835);
DISPLAY 0.680851 (4315 1835);
PAINT MONO (4315 1835);
FORCEPROP 0 LASTPIN (4325 1875) $PN 193
J 2
(4315 1885);
DISPLAY 0.680851 (4315 1885);
PAINT MONO (4315 1885);
FORCEPROP 0 LASTPIN (4325 1925) $PN 195
J 2
(4315 1935);
DISPLAY 0.680851 (4315 1935);
PAINT MONO (4315 1935);
FORCEPROP 0 LASTPIN (4325 1975) $PN 197
J 2
(4315 1985);
DISPLAY 0.680851 (4315 1985);
PAINT MONO (4315 1985);
FORCEPROP 0 LASTPIN (4325 2025) $PN 199
J 2
(4315 2035);
DISPLAY 0.680851 (4315 2035);
PAINT MONO (4315 2035);
FORCEPROP 0 LASTPIN (4325 2075) $PN 202
J 2
(4315 2085);
DISPLAY 0.680851 (4315 2085);
PAINT MONO (4315 2085);
FORCEPROP 0 LASTPIN (4325 2125) $PN 204
J 2
(4315 2135);
DISPLAY 0.680851 (4315 2135);
PAINT MONO (4315 2135);
FORCEPROP 0 LASTPIN (4325 2175) $PN 206
J 2
(4315 2185);
DISPLAY 0.680851 (4315 2185);
PAINT MONO (4315 2185);
FORCEPROP 0 LASTPIN (4325 2225) $PN 208
J 2
(4315 2235);
DISPLAY 0.680851 (4315 2235);
PAINT MONO (4315 2235);
FORCEPROP 0 LASTPIN (4325 2275) $PN 210
J 2
(4315 2285);
DISPLAY 0.680851 (4315 2285);
PAINT MONO (4315 2285);
FORCEPROP 0 LASTPIN (4325 2325) $PN 212
J 2
(4315 2335);
DISPLAY 0.680851 (4315 2335);
PAINT MONO (4315 2335);
FORCEPROP 0 LASTPIN (4325 2375) $PN 214
J 2
(4315 2385);
DISPLAY 0.680851 (4315 2385);
PAINT MONO (4315 2385);
FORCEPROP 0 LASTPIN (4325 2425) $PN 216
J 2
(4315 2435);
DISPLAY 0.680851 (4315 2435);
PAINT MONO (4315 2435);
FORCEPROP 0 LASTPIN (4325 2475) $PN 219
J 2
(4315 2485);
DISPLAY 0.680851 (4315 2485);
PAINT MONO (4315 2485);
FORCEPROP 0 LASTPIN (4325 2525) $PN 222
J 2
(4315 2535);
DISPLAY 0.680851 (4315 2535);
PAINT MONO (4315 2535);
FORCEPROP 0 LASTPIN (4325 2575) $PN 224
J 2
(4315 2585);
DISPLAY 0.680851 (4315 2585);
PAINT MONO (4315 2585);
FORCEPROP 0 LASTPIN (4325 2625) $PN 226
J 2
(4315 2635);
DISPLAY 0.680851 (4315 2635);
PAINT MONO (4315 2635);
FORCEPROP 0 LASTPIN (4325 2675) $PN 228
J 2
(4315 2685);
DISPLAY 0.680851 (4315 2685);
PAINT MONO (4315 2685);
FORCEPROP 0 LASTPIN (4325 2725) $PN 230
J 2
(4315 2735);
DISPLAY 0.680851 (4315 2735);
PAINT MONO (4315 2735);
FORCEPROP 0 LASTPIN (4325 2775) $PN 233
J 2
(4315 2785);
DISPLAY 0.680851 (4315 2785);
PAINT MONO (4315 2785);
FORCEPROP 0 LASTPIN (4325 2825) $PN 235
J 2
(4315 2835);
DISPLAY 0.680851 (4315 2835);
PAINT MONO (4315 2835);
FORCEPROP 0 LASTPIN (4325 2875) $PN 237
J 2
(4315 2885);
DISPLAY 0.680851 (4315 2885);
PAINT MONO (4315 2885);
FORCEPROP 0 LASTPIN (4325 2925) $PN 240
J 2
(4315 2935);
DISPLAY 0.680851 (4315 2935);
PAINT MONO (4315 2935);
FORCEPROP 0 LASTPIN (4325 2975) $PN 242
J 2
(4315 2985);
DISPLAY 0.680851 (4315 2985);
PAINT MONO (4315 2985);
FORCEPROP 0 LASTPIN (4325 3025) $PN 244
J 2
(4315 3035);
DISPLAY 0.680851 (4315 3035);
PAINT MONO (4315 3035);
FORCEPROP 0 LASTPIN (4325 3075) $PN 246
J 2
(4315 3085);
DISPLAY 0.680851 (4315 3085);
PAINT MONO (4315 3085);
FORCEPROP 0 LASTPIN (4325 3125) $PN 248
J 2
(4315 3135);
DISPLAY 0.680851 (4315 3135);
PAINT MONO (4315 3135);
FORCEPROP 0 LASTPIN (4325 3175) $PN 251
J 2
(4315 3185);
DISPLAY 0.680851 (4315 3185);
PAINT MONO (4315 3185);
FORCEPROP 0 LASTPIN (4325 3225) $PN 253
J 2
(4315 3235);
DISPLAY 0.680851 (4315 3235);
PAINT MONO (4315 3235);
FORCEPROP 0 LASTPIN (4325 3275) $PN 255
J 2
(4315 3285);
DISPLAY 0.680851 (4315 3285);
PAINT MONO (4315 3285);
FORCEPROP 0 LASTPIN (4325 3325) $PN 257
J 2
(4315 3335);
DISPLAY 0.680851 (4315 3335);
PAINT MONO (4315 3335);
FORCEPROP 0 LASTPIN (4325 3375) $PN 259
J 2
(4315 3385);
DISPLAY 0.680851 (4315 3385);
PAINT MONO (4315 3385);
FORCEPROP 0 LASTPIN (4325 3425) $PN 262
J 2
(4315 3435);
DISPLAY 0.680851 (4315 3435);
PAINT MONO (4315 3435);
FORCEPROP 0 LASTPIN (4325 3475) $PN 264
J 2
(4315 3485);
DISPLAY 0.680851 (4315 3485);
PAINT MONO (4315 3485);
FORCEPROP 0 LASTPIN (4325 3525) $PN 266
J 2
(4315 3535);
DISPLAY 0.680851 (4315 3535);
PAINT MONO (4315 3535);
FORCEPROP 0 LASTPIN (4325 3575) $PN 268
J 2
(4315 3585);
DISPLAY 0.680851 (4315 3585);
PAINT MONO (4315 3585);
FORCEPROP 0 LASTPIN (4325 3625) $PN 270
J 2
(4315 3635);
DISPLAY 0.680851 (4315 3635);
PAINT MONO (4315 3635);
FORCEPROP 0 LASTPIN (4325 3675) $PN 273
J 2
(4315 3685);
DISPLAY 0.680851 (4315 3685);
PAINT MONO (4315 3685);
FORCEPROP 0 LASTPIN (4325 3725) $PN 275
J 2
(4315 3735);
DISPLAY 0.680851 (4315 3735);
PAINT MONO (4315 3735);
FORCEPROP 0 LASTPIN (4325 3775) $PN 277
J 2
(4315 3785);
DISPLAY 0.680851 (4315 3785);
PAINT MONO (4315 3785);
FORCEPROP 0 LASTPIN (4325 3825) $PN 279
J 2
(4315 3835);
DISPLAY 0.680851 (4315 3835);
PAINT MONO (4315 3835);
FORCEPROP 0 LASTPIN (4325 3875) $PN 281
J 2
(4315 3885);
DISPLAY 0.680851 (4315 3885);
PAINT MONO (4315 3885);
FORCEPROP 0 LASTPIN (4325 3925) $PN 284
J 2
(4315 3935);
DISPLAY 0.680851 (4315 3935);
PAINT MONO (4315 3935);
FORCEPROP 0 LASTPIN (4325 3975) $PN 286
J 2
(4315 3985);
DISPLAY 0.680851 (4315 3985);
PAINT MONO (4315 3985);
FORCEPROP 0 LASTPIN (4325 4025) $PN 288
J 2
(4315 4035);
DISPLAY 0.680851 (4315 4035);
PAINT MONO (4315 4035);
FORCEPROP 1 LAST NEEDS_NO_SIZE TRUE
J 0
(4925 2550);
DISPLAY 0.723404 (4925 2550);
PAINT GREEN (4925 2550);
DISPLAY INVISIBLE (4925 2550);
FORCEPROP 1 LAST CDS_LMAN_SYM_OUTLINE -450,1775,450,-1775
J 0
(4925 2550);
DISPLAY 0.468085 (4925 2550);
PAINT GREEN (4925 2550);
DISPLAY INVISIBLE (4925 2550);
FORCEPROP 2 LAST CDS_LIB pure_quanta
J 0
(4925 2550);
DISPLAY INVISIBLE (4925 2550);
FORCEPROP 2 LAST CDS_LOCATION J16
J 0
(4475 4675);
DISPLAY 1.021277 (4475 4675);
DISPLAY INVISIBLE (4475 4675);
FORCEPROP 0 LAST $SEC 3
J 0
(4475 4675);
DISPLAY 0.680851 (4475 4675);
PAINT MONO (4475 4675);
DISPLAY INVISIBLE (4475 4675);
FORCEPROP 2 LAST CDS_SEC 3
J 0
(4475 4675);
DISPLAY 1.021277 (4475 4675);
DISPLAY INVISIBLE (4475 4675);
FORCEPROP 1 LAST PATH I64
J 0
(4925 2550);
DISPLAY 0.723404 (4925 2550);
PAINT GREEN (4925 2550);
DISPLAY INVISIBLE (4925 2550);
FORCEADD UNIVERSAL_GND..1
(5775 475);
FORCEPROP 3 LASTPIN (5775 525) SIG_NAME GND\g
J 0
(5785 535);
DISPLAY 0.659574 (5785 535);
PAINT MONO (5785 535);
DISPLAY INVISIBLE (5785 535);
FORCEPROP 2 LAST CDS_LIB logical_power
J 0
(5775 475);
PAINT MONO (5775 475);
DISPLAY INVISIBLE (5775 475);
FORCEPROP 1 LAST HDL_POWER GND
J 1
(5800 400);
DISPLAY 0.872340 (5800 400);
PAINT GREEN (5800 400);
DISPLAY INVISIBLE (5800 400);
FORCEPROP 1 LAST PATH I65
J 0
(5850 475);
DISPLAY 0.872340 (5850 475);
PAINT AQUA (5850 475);
DISPLAY INVISIBLE (5850 475);
FORCEADD TAP..1
(-350 975);
FORCEPROP 3 LASTPIN (-400 975) SIG_NAME M_H_CPU0_SB_DQ<0>
J 0
(-390 985);
DISPLAY 0.659574 (-390 985);
PAINT MONO (-390 985);
DISPLAY INVISIBLE (-390 985);
FORCEPROP 1 LASTPIN (-400 975) BN 0
J 0
(-412 983);
DISPLAY 0.680851 (-412 983);
PAINT GREEN (-412 983);
FORCEPROP 2 LAST CDS_LIB standard
J 0
(-350 975);
PAINT MONO (-350 975);
DISPLAY INVISIBLE (-350 975);
FORCEPROP 1 LAST BODY_TYPE PLUMBING
J 0
(-350 1025);
DISPLAY 0.872340 (-350 1025);
PAINT GREEN (-350 1025);
DISPLAY INVISIBLE (-350 1025);
FORCEPROP 1 LAST HDL_TAP TRUE
J 0
(-25 850);
DISPLAY 0.872340 (-25 850);
DISPLAY INVISIBLE (-25 850);
FORCEPROP 1 LAST PATH I66
J 0
(-352 975);
DISPLAY 0.872340 (-352 975);
PAINT GREEN (-352 975);
DISPLAY INVISIBLE (-352 975);
FORCEADD TAP..1
(-350 1025);
FORCEPROP 3 LASTPIN (-400 1025) SIG_NAME M_H_CPU0_SB_DQ<1>
J 0
(-390 1035);
DISPLAY 0.659574 (-390 1035);
PAINT MONO (-390 1035);
DISPLAY INVISIBLE (-390 1035);
FORCEPROP 1 LASTPIN (-400 1025) BN 1
J 0
(-412 1033);
DISPLAY 0.680851 (-412 1033);
PAINT GREEN (-412 1033);
FORCEPROP 2 LAST CDS_LIB standard
J 0
(-350 1025);
PAINT MONO (-350 1025);
DISPLAY INVISIBLE (-350 1025);
FORCEPROP 1 LAST BODY_TYPE PLUMBING
J 0
(-350 1075);
DISPLAY 0.872340 (-350 1075);
PAINT GREEN (-350 1075);
DISPLAY INVISIBLE (-350 1075);
FORCEPROP 1 LAST HDL_TAP TRUE
J 0
(-25 900);
DISPLAY 0.872340 (-25 900);
DISPLAY INVISIBLE (-25 900);
FORCEPROP 1 LAST PATH I67
J 0
(-352 1025);
DISPLAY 0.872340 (-352 1025);
PAINT GREEN (-352 1025);
DISPLAY INVISIBLE (-352 1025);
FORCEADD TAP..1
(-350 1075);
FORCEPROP 3 LASTPIN (-400 1075) SIG_NAME M_H_CPU0_SB_DQ<2>
J 0
(-390 1085);
DISPLAY 0.659574 (-390 1085);
PAINT MONO (-390 1085);
DISPLAY INVISIBLE (-390 1085);
FORCEPROP 1 LASTPIN (-400 1075) BN 2
J 0
(-412 1083);
DISPLAY 0.680851 (-412 1083);
PAINT GREEN (-412 1083);
FORCEPROP 2 LAST CDS_LIB standard
J 0
(-350 1075);
PAINT MONO (-350 1075);
DISPLAY INVISIBLE (-350 1075);
FORCEPROP 1 LAST BODY_TYPE PLUMBING
J 0
(-350 1125);
DISPLAY 0.872340 (-350 1125);
PAINT GREEN (-350 1125);
DISPLAY INVISIBLE (-350 1125);
FORCEPROP 1 LAST HDL_TAP TRUE
J 0
(-25 950);
DISPLAY 0.872340 (-25 950);
DISPLAY INVISIBLE (-25 950);
FORCEPROP 1 LAST PATH I68
J 0
(-352 1075);
DISPLAY 0.872340 (-352 1075);
PAINT GREEN (-352 1075);
DISPLAY INVISIBLE (-352 1075);
FORCEADD TAP..1
(-350 1125);
FORCEPROP 3 LASTPIN (-400 1125) SIG_NAME M_H_CPU0_SB_DQ<3>
J 0
(-390 1135);
DISPLAY 0.659574 (-390 1135);
PAINT MONO (-390 1135);
DISPLAY INVISIBLE (-390 1135);
FORCEPROP 1 LASTPIN (-400 1125) BN 3
J 0
(-412 1133);
DISPLAY 0.680851 (-412 1133);
PAINT GREEN (-412 1133);
FORCEPROP 2 LAST CDS_LIB standard
J 0
(-350 1125);
PAINT MONO (-350 1125);
DISPLAY INVISIBLE (-350 1125);
FORCEPROP 1 LAST BODY_TYPE PLUMBING
J 0
(-350 1175);
DISPLAY 0.872340 (-350 1175);
PAINT GREEN (-350 1175);
DISPLAY INVISIBLE (-350 1175);
FORCEPROP 1 LAST HDL_TAP TRUE
J 0
(-25 1000);
DISPLAY 0.872340 (-25 1000);
DISPLAY INVISIBLE (-25 1000);
FORCEPROP 1 LAST PATH I69
J 0
(-352 1125);
DISPLAY 0.872340 (-352 1125);
PAINT GREEN (-352 1125);
DISPLAY INVISIBLE (-352 1125);
FORCEADD OFFPAGE..3
R 2
(-2925 1300);
FORCEPROP 2 LAST $XR0 114 
J 0
(-3205 1300);
DISPLAY 0.638298 (-3205 1300);
PAINT MONO (-3205 1300);
FORCEPROP 2 LAST CDS_LIB standard
J 0
(-2925 1300);
PAINT MONO (-2925 1300);
DISPLAY INVISIBLE (-2925 1300);
FORCEPROP 1 LAST OFFPAGE TRUE
J 2
(-3250 1175);
DISPLAY 0.872340 (-3250 1175);
DISPLAY INVISIBLE (-3250 1175);
FORCEPROP 1 LAST COMMENT_BODY TRUE
J 2
(-2875 1200);
DISPLAY 0.872340 (-2875 1200);
PAINT GREEN (-2875 1200);
DISPLAY INVISIBLE (-2875 1200);
FORCEPROP 2 LAST PATH I7
J 0
(-2875 1375);
DISPLAY 1.021277 (-2875 1375);
DISPLAY INVISIBLE (-2875 1375);
FORCEADD TAP..1
(-350 1225);
FORCEPROP 3 LASTPIN (-400 1225) SIG_NAME M_H_CPU0_SB_DQ<5>
J 0
(-390 1235);
DISPLAY 0.659574 (-390 1235);
PAINT MONO (-390 1235);
DISPLAY INVISIBLE (-390 1235);
FORCEPROP 1 LASTPIN (-400 1225) BN 5
J 0
(-412 1233);
DISPLAY 0.680851 (-412 1233);
PAINT GREEN (-412 1233);
FORCEPROP 2 LAST CDS_LIB standard
J 0
(-350 1225);
PAINT MONO (-350 1225);
DISPLAY INVISIBLE (-350 1225);
FORCEPROP 1 LAST BODY_TYPE PLUMBING
J 0
(-350 1275);
DISPLAY 0.872340 (-350 1275);
PAINT GREEN (-350 1275);
DISPLAY INVISIBLE (-350 1275);
FORCEPROP 1 LAST HDL_TAP TRUE
J 0
(-25 1100);
DISPLAY 0.872340 (-25 1100);
DISPLAY INVISIBLE (-25 1100);
FORCEPROP 1 LAST PATH I70
J 0
(-352 1225);
DISPLAY 0.872340 (-352 1225);
PAINT GREEN (-352 1225);
DISPLAY INVISIBLE (-352 1225);
FORCEADD TAP..1
(-350 1175);
FORCEPROP 3 LASTPIN (-400 1175) SIG_NAME M_H_CPU0_SB_DQ<4>
J 0
(-390 1185);
DISPLAY 0.659574 (-390 1185);
PAINT MONO (-390 1185);
DISPLAY INVISIBLE (-390 1185);
FORCEPROP 1 LASTPIN (-400 1175) BN 4
J 0
(-412 1183);
DISPLAY 0.680851 (-412 1183);
PAINT GREEN (-412 1183);
FORCEPROP 2 LAST CDS_LIB standard
J 0
(-350 1175);
PAINT MONO (-350 1175);
DISPLAY INVISIBLE (-350 1175);
FORCEPROP 1 LAST BODY_TYPE PLUMBING
J 0
(-350 1225);
DISPLAY 0.872340 (-350 1225);
PAINT GREEN (-350 1225);
DISPLAY INVISIBLE (-350 1225);
FORCEPROP 1 LAST HDL_TAP TRUE
J 0
(-25 1050);
DISPLAY 0.872340 (-25 1050);
DISPLAY INVISIBLE (-25 1050);
FORCEPROP 1 LAST PATH I71
J 0
(-352 1175);
DISPLAY 0.872340 (-352 1175);
PAINT GREEN (-352 1175);
DISPLAY INVISIBLE (-352 1175);
FORCEADD TAP..1
(-350 1325);
FORCEPROP 3 LASTPIN (-400 1325) SIG_NAME M_H_CPU0_SB_DQ<7>
J 0
(-390 1335);
DISPLAY 0.659574 (-390 1335);
PAINT MONO (-390 1335);
DISPLAY INVISIBLE (-390 1335);
FORCEPROP 1 LASTPIN (-400 1325) BN 7
J 0
(-412 1333);
DISPLAY 0.680851 (-412 1333);
PAINT GREEN (-412 1333);
FORCEPROP 2 LAST CDS_LIB standard
J 0
(-350 1325);
PAINT MONO (-350 1325);
DISPLAY INVISIBLE (-350 1325);
FORCEPROP 1 LAST BODY_TYPE PLUMBING
J 0
(-350 1375);
DISPLAY 0.872340 (-350 1375);
PAINT GREEN (-350 1375);
DISPLAY INVISIBLE (-350 1375);
FORCEPROP 1 LAST HDL_TAP TRUE
J 0
(-25 1200);
DISPLAY 0.872340 (-25 1200);
DISPLAY INVISIBLE (-25 1200);
FORCEPROP 1 LAST PATH I72
J 0
(-352 1325);
DISPLAY 0.872340 (-352 1325);
PAINT GREEN (-352 1325);
DISPLAY INVISIBLE (-352 1325);
FORCEADD TAP..1
(-350 1275);
FORCEPROP 3 LASTPIN (-400 1275) SIG_NAME M_H_CPU0_SB_DQ<6>
J 0
(-390 1285);
DISPLAY 0.659574 (-390 1285);
PAINT MONO (-390 1285);
DISPLAY INVISIBLE (-390 1285);
FORCEPROP 1 LASTPIN (-400 1275) BN 6
J 0
(-412 1283);
DISPLAY 0.680851 (-412 1283);
PAINT GREEN (-412 1283);
FORCEPROP 2 LAST CDS_LIB standard
J 0
(-350 1275);
PAINT MONO (-350 1275);
DISPLAY INVISIBLE (-350 1275);
FORCEPROP 1 LAST BODY_TYPE PLUMBING
J 0
(-350 1325);
DISPLAY 0.872340 (-350 1325);
PAINT GREEN (-350 1325);
DISPLAY INVISIBLE (-350 1325);
FORCEPROP 1 LAST HDL_TAP TRUE
J 0
(-25 1150);
DISPLAY 0.872340 (-25 1150);
DISPLAY INVISIBLE (-25 1150);
FORCEPROP 1 LAST PATH I73
J 0
(-352 1275);
DISPLAY 0.872340 (-352 1275);
PAINT GREEN (-352 1275);
DISPLAY INVISIBLE (-352 1275);
FORCEADD TAP..1
(-350 1425);
FORCEPROP 3 LASTPIN (-400 1425) SIG_NAME M_H_CPU0_SB_DQ<9>
J 0
(-390 1435);
DISPLAY 0.659574 (-390 1435);
PAINT MONO (-390 1435);
DISPLAY INVISIBLE (-390 1435);
FORCEPROP 1 LASTPIN (-400 1425) BN 9
J 0
(-412 1433);
DISPLAY 0.680851 (-412 1433);
PAINT GREEN (-412 1433);
FORCEPROP 2 LAST CDS_LIB standard
J 0
(-350 1425);
PAINT MONO (-350 1425);
DISPLAY INVISIBLE (-350 1425);
FORCEPROP 1 LAST BODY_TYPE PLUMBING
J 0
(-350 1475);
DISPLAY 0.872340 (-350 1475);
PAINT GREEN (-350 1475);
DISPLAY INVISIBLE (-350 1475);
FORCEPROP 1 LAST HDL_TAP TRUE
J 0
(-25 1300);
DISPLAY 0.872340 (-25 1300);
DISPLAY INVISIBLE (-25 1300);
FORCEPROP 1 LAST PATH I74
J 0
(-352 1425);
DISPLAY 0.872340 (-352 1425);
PAINT GREEN (-352 1425);
DISPLAY INVISIBLE (-352 1425);
FORCEADD TAP..1
(-350 1375);
FORCEPROP 3 LASTPIN (-400 1375) SIG_NAME M_H_CPU0_SB_DQ<8>
J 0
(-390 1385);
DISPLAY 0.659574 (-390 1385);
PAINT MONO (-390 1385);
DISPLAY INVISIBLE (-390 1385);
FORCEPROP 1 LASTPIN (-400 1375) BN 8
J 0
(-412 1383);
DISPLAY 0.680851 (-412 1383);
PAINT GREEN (-412 1383);
FORCEPROP 2 LAST CDS_LIB standard
J 0
(-350 1375);
PAINT MONO (-350 1375);
DISPLAY INVISIBLE (-350 1375);
FORCEPROP 1 LAST BODY_TYPE PLUMBING
J 0
(-350 1425);
DISPLAY 0.872340 (-350 1425);
PAINT GREEN (-350 1425);
DISPLAY INVISIBLE (-350 1425);
FORCEPROP 1 LAST HDL_TAP TRUE
J 0
(-25 1250);
DISPLAY 0.872340 (-25 1250);
DISPLAY INVISIBLE (-25 1250);
FORCEPROP 1 LAST PATH I75
J 0
(-352 1375);
DISPLAY 0.872340 (-352 1375);
PAINT GREEN (-352 1375);
DISPLAY INVISIBLE (-352 1375);
FORCEADD TAP..1
(-350 1475);
FORCEPROP 3 LASTPIN (-400 1475) SIG_NAME M_H_CPU0_SB_DQ<10>
J 0
(-390 1485);
DISPLAY 0.659574 (-390 1485);
PAINT MONO (-390 1485);
DISPLAY INVISIBLE (-390 1485);
FORCEPROP 1 LASTPIN (-400 1475) BN 10
J 0
(-412 1483);
DISPLAY 0.680851 (-412 1483);
PAINT GREEN (-412 1483);
FORCEPROP 2 LAST CDS_LIB standard
J 0
(-350 1475);
PAINT MONO (-350 1475);
DISPLAY INVISIBLE (-350 1475);
FORCEPROP 1 LAST BODY_TYPE PLUMBING
J 0
(-350 1525);
DISPLAY 0.872340 (-350 1525);
PAINT GREEN (-350 1525);
DISPLAY INVISIBLE (-350 1525);
FORCEPROP 1 LAST HDL_TAP TRUE
J 0
(-25 1350);
DISPLAY 0.872340 (-25 1350);
DISPLAY INVISIBLE (-25 1350);
FORCEPROP 1 LAST PATH I76
J 0
(-352 1475);
DISPLAY 0.872340 (-352 1475);
PAINT GREEN (-352 1475);
DISPLAY INVISIBLE (-352 1475);
FORCEADD TAP..1
(-350 1575);
FORCEPROP 3 LASTPIN (-400 1575) SIG_NAME M_H_CPU0_SB_DQ<12>
J 0
(-390 1585);
DISPLAY 0.659574 (-390 1585);
PAINT MONO (-390 1585);
DISPLAY INVISIBLE (-390 1585);
FORCEPROP 1 LASTPIN (-400 1575) BN 12
J 0
(-412 1583);
DISPLAY 0.680851 (-412 1583);
PAINT GREEN (-412 1583);
FORCEPROP 2 LAST CDS_LIB standard
J 0
(-350 1575);
PAINT MONO (-350 1575);
DISPLAY INVISIBLE (-350 1575);
FORCEPROP 1 LAST BODY_TYPE PLUMBING
J 0
(-350 1625);
DISPLAY 0.872340 (-350 1625);
PAINT GREEN (-350 1625);
DISPLAY INVISIBLE (-350 1625);
FORCEPROP 1 LAST HDL_TAP TRUE
J 0
(-25 1450);
DISPLAY 0.872340 (-25 1450);
DISPLAY INVISIBLE (-25 1450);
FORCEPROP 1 LAST PATH I77
J 0
(-352 1575);
DISPLAY 0.872340 (-352 1575);
PAINT GREEN (-352 1575);
DISPLAY INVISIBLE (-352 1575);
FORCEADD TAP..1
(-350 1525);
FORCEPROP 3 LASTPIN (-400 1525) SIG_NAME M_H_CPU0_SB_DQ<11>
J 0
(-390 1535);
DISPLAY 0.659574 (-390 1535);
PAINT MONO (-390 1535);
DISPLAY INVISIBLE (-390 1535);
FORCEPROP 1 LASTPIN (-400 1525) BN 11
J 0
(-412 1533);
DISPLAY 0.680851 (-412 1533);
PAINT GREEN (-412 1533);
FORCEPROP 2 LAST CDS_LIB standard
J 0
(-350 1525);
PAINT MONO (-350 1525);
DISPLAY INVISIBLE (-350 1525);
FORCEPROP 1 LAST BODY_TYPE PLUMBING
J 0
(-350 1575);
DISPLAY 0.872340 (-350 1575);
PAINT GREEN (-350 1575);
DISPLAY INVISIBLE (-350 1575);
FORCEPROP 1 LAST HDL_TAP TRUE
J 0
(-25 1400);
DISPLAY 0.872340 (-25 1400);
DISPLAY INVISIBLE (-25 1400);
FORCEPROP 1 LAST PATH I78
J 0
(-352 1525);
DISPLAY 0.872340 (-352 1525);
PAINT GREEN (-352 1525);
DISPLAY INVISIBLE (-352 1525);
FORCEADD TAP..1
(-350 1675);
FORCEPROP 3 LASTPIN (-400 1675) SIG_NAME M_H_CPU0_SB_DQ<14>
J 0
(-390 1685);
DISPLAY 0.659574 (-390 1685);
PAINT MONO (-390 1685);
DISPLAY INVISIBLE (-390 1685);
FORCEPROP 1 LASTPIN (-400 1675) BN 14
J 0
(-412 1683);
DISPLAY 0.680851 (-412 1683);
PAINT GREEN (-412 1683);
FORCEPROP 2 LAST CDS_LIB standard
J 0
(-350 1675);
PAINT MONO (-350 1675);
DISPLAY INVISIBLE (-350 1675);
FORCEPROP 1 LAST BODY_TYPE PLUMBING
J 0
(-350 1725);
DISPLAY 0.872340 (-350 1725);
PAINT GREEN (-350 1725);
DISPLAY INVISIBLE (-350 1725);
FORCEPROP 1 LAST HDL_TAP TRUE
J 0
(-25 1550);
DISPLAY 0.872340 (-25 1550);
DISPLAY INVISIBLE (-25 1550);
FORCEPROP 1 LAST PATH I79
J 0
(-352 1675);
DISPLAY 0.872340 (-352 1675);
PAINT GREEN (-352 1675);
DISPLAY INVISIBLE (-352 1675);
FORCEADD OFFPAGE..1
(-2925 1800);
FORCEPROP 2 LAST $XR1 96 
J 0
(-3236 1800);
DISPLAY 0.638298 (-3236 1800);
PAINT MONO (-3236 1800);
FORCEPROP 2 LAST $XR0 27 
J 0
(-3146 1800);
DISPLAY 0.638298 (-3146 1800);
PAINT MONO (-3146 1800);
FORCEPROP 2 LAST CDS_LIB standard
J 0
(-2925 1800);
PAINT MONO (-2925 1800);
DISPLAY INVISIBLE (-2925 1800);
FORCEPROP 1 LAST OFFPAGE TRUE
J 0
(-2600 1675);
DISPLAY 0.872340 (-2600 1675);
DISPLAY INVISIBLE (-2600 1675);
FORCEPROP 1 LAST COMMENT_BODY TRUE
J 0
(-2800 1700);
DISPLAY 0.872340 (-2800 1700);
PAINT GREEN (-2800 1700);
DISPLAY INVISIBLE (-2800 1700);
FORCEPROP 2 LAST PATH I8
J 0
(-2875 1875);
DISPLAY 1.021277 (-2875 1875);
DISPLAY INVISIBLE (-2875 1875);
FORCEADD TAP..1
(-350 1625);
FORCEPROP 3 LASTPIN (-400 1625) SIG_NAME M_H_CPU0_SB_DQ<13>
J 0
(-390 1635);
DISPLAY 0.659574 (-390 1635);
PAINT MONO (-390 1635);
DISPLAY INVISIBLE (-390 1635);
FORCEPROP 1 LASTPIN (-400 1625) BN 13
J 0
(-412 1633);
DISPLAY 0.680851 (-412 1633);
PAINT GREEN (-412 1633);
FORCEPROP 2 LAST CDS_LIB standard
J 0
(-350 1625);
PAINT MONO (-350 1625);
DISPLAY INVISIBLE (-350 1625);
FORCEPROP 1 LAST BODY_TYPE PLUMBING
J 0
(-350 1675);
DISPLAY 0.872340 (-350 1675);
PAINT GREEN (-350 1675);
DISPLAY INVISIBLE (-350 1675);
FORCEPROP 1 LAST HDL_TAP TRUE
J 0
(-25 1500);
DISPLAY 0.872340 (-25 1500);
DISPLAY INVISIBLE (-25 1500);
FORCEPROP 1 LAST PATH I80
J 0
(-352 1625);
DISPLAY 0.872340 (-352 1625);
PAINT GREEN (-352 1625);
DISPLAY INVISIBLE (-352 1625);
FORCEADD TAP..1
(-350 1725);
FORCEPROP 3 LASTPIN (-400 1725) SIG_NAME M_H_CPU0_SB_DQ<15>
J 0
(-390 1735);
DISPLAY 0.659574 (-390 1735);
PAINT MONO (-390 1735);
DISPLAY INVISIBLE (-390 1735);
FORCEPROP 1 LASTPIN (-400 1725) BN 15
J 0
(-412 1733);
DISPLAY 0.680851 (-412 1733);
PAINT GREEN (-412 1733);
FORCEPROP 2 LAST CDS_LIB standard
J 0
(-350 1725);
PAINT MONO (-350 1725);
DISPLAY INVISIBLE (-350 1725);
FORCEPROP 1 LAST BODY_TYPE PLUMBING
J 0
(-350 1775);
DISPLAY 0.872340 (-350 1775);
PAINT GREEN (-350 1775);
DISPLAY INVISIBLE (-350 1775);
FORCEPROP 1 LAST HDL_TAP TRUE
J 0
(-25 1600);
DISPLAY 0.872340 (-25 1600);
DISPLAY INVISIBLE (-25 1600);
FORCEPROP 1 LAST PATH I81
J 0
(-352 1725);
DISPLAY 0.872340 (-352 1725);
PAINT GREEN (-352 1725);
DISPLAY INVISIBLE (-352 1725);
FORCEADD TAP..1
(-350 1825);
FORCEPROP 3 LASTPIN (-400 1825) SIG_NAME M_H_CPU0_SB_DQ<17>
J 0
(-390 1835);
DISPLAY 0.659574 (-390 1835);
PAINT MONO (-390 1835);
DISPLAY INVISIBLE (-390 1835);
FORCEPROP 1 LASTPIN (-400 1825) BN 17
J 0
(-412 1833);
DISPLAY 0.680851 (-412 1833);
PAINT GREEN (-412 1833);
FORCEPROP 2 LAST CDS_LIB standard
J 0
(-350 1825);
PAINT MONO (-350 1825);
DISPLAY INVISIBLE (-350 1825);
FORCEPROP 1 LAST BODY_TYPE PLUMBING
J 0
(-350 1875);
DISPLAY 0.872340 (-350 1875);
PAINT GREEN (-350 1875);
DISPLAY INVISIBLE (-350 1875);
FORCEPROP 1 LAST HDL_TAP TRUE
J 0
(-25 1700);
DISPLAY 0.872340 (-25 1700);
DISPLAY INVISIBLE (-25 1700);
FORCEPROP 1 LAST PATH I82
J 0
(-352 1825);
DISPLAY 0.872340 (-352 1825);
PAINT GREEN (-352 1825);
DISPLAY INVISIBLE (-352 1825);
FORCEADD TAP..1
(-350 1775);
FORCEPROP 3 LASTPIN (-400 1775) SIG_NAME M_H_CPU0_SB_DQ<16>
J 0
(-390 1785);
DISPLAY 0.659574 (-390 1785);
PAINT MONO (-390 1785);
DISPLAY INVISIBLE (-390 1785);
FORCEPROP 1 LASTPIN (-400 1775) BN 16
J 0
(-412 1783);
DISPLAY 0.680851 (-412 1783);
PAINT GREEN (-412 1783);
FORCEPROP 2 LAST CDS_LIB standard
J 0
(-350 1775);
PAINT MONO (-350 1775);
DISPLAY INVISIBLE (-350 1775);
FORCEPROP 1 LAST BODY_TYPE PLUMBING
J 0
(-350 1825);
DISPLAY 0.872340 (-350 1825);
PAINT GREEN (-350 1825);
DISPLAY INVISIBLE (-350 1825);
FORCEPROP 1 LAST HDL_TAP TRUE
J 0
(-25 1650);
DISPLAY 0.872340 (-25 1650);
DISPLAY INVISIBLE (-25 1650);
FORCEPROP 1 LAST PATH I83
J 0
(-352 1775);
DISPLAY 0.872340 (-352 1775);
PAINT GREEN (-352 1775);
DISPLAY INVISIBLE (-352 1775);
FORCEADD TAP..1
(-350 1875);
FORCEPROP 3 LASTPIN (-400 1875) SIG_NAME M_H_CPU0_SB_DQ<18>
J 0
(-390 1885);
DISPLAY 0.659574 (-390 1885);
PAINT MONO (-390 1885);
DISPLAY INVISIBLE (-390 1885);
FORCEPROP 1 LASTPIN (-400 1875) BN 18
J 0
(-412 1883);
DISPLAY 0.680851 (-412 1883);
PAINT GREEN (-412 1883);
FORCEPROP 2 LAST CDS_LIB standard
J 0
(-350 1875);
PAINT MONO (-350 1875);
DISPLAY INVISIBLE (-350 1875);
FORCEPROP 1 LAST BODY_TYPE PLUMBING
J 0
(-350 1925);
DISPLAY 0.872340 (-350 1925);
PAINT GREEN (-350 1925);
DISPLAY INVISIBLE (-350 1925);
FORCEPROP 1 LAST HDL_TAP TRUE
J 0
(-25 1750);
DISPLAY 0.872340 (-25 1750);
DISPLAY INVISIBLE (-25 1750);
FORCEPROP 1 LAST PATH I84
J 0
(-352 1875);
DISPLAY 0.872340 (-352 1875);
PAINT GREEN (-352 1875);
DISPLAY INVISIBLE (-352 1875);
FORCEADD TAP..1
(-350 1925);
FORCEPROP 3 LASTPIN (-400 1925) SIG_NAME M_H_CPU0_SB_DQ<19>
J 0
(-390 1935);
DISPLAY 0.659574 (-390 1935);
PAINT MONO (-390 1935);
DISPLAY INVISIBLE (-390 1935);
FORCEPROP 1 LASTPIN (-400 1925) BN 19
J 0
(-412 1933);
DISPLAY 0.680851 (-412 1933);
PAINT GREEN (-412 1933);
FORCEPROP 2 LAST CDS_LIB standard
J 0
(-350 1925);
PAINT MONO (-350 1925);
DISPLAY INVISIBLE (-350 1925);
FORCEPROP 1 LAST BODY_TYPE PLUMBING
J 0
(-350 1975);
DISPLAY 0.872340 (-350 1975);
PAINT GREEN (-350 1975);
DISPLAY INVISIBLE (-350 1975);
FORCEPROP 1 LAST HDL_TAP TRUE
J 0
(-25 1800);
DISPLAY 0.872340 (-25 1800);
DISPLAY INVISIBLE (-25 1800);
FORCEPROP 1 LAST PATH I85
J 0
(-352 1925);
DISPLAY 0.872340 (-352 1925);
PAINT GREEN (-352 1925);
DISPLAY INVISIBLE (-352 1925);
FORCEADD TAP..1
(-350 1975);
FORCEPROP 3 LASTPIN (-400 1975) SIG_NAME M_H_CPU0_SB_DQ<20>
J 0
(-390 1985);
DISPLAY 0.659574 (-390 1985);
PAINT MONO (-390 1985);
DISPLAY INVISIBLE (-390 1985);
FORCEPROP 1 LASTPIN (-400 1975) BN 20
J 0
(-412 1983);
DISPLAY 0.680851 (-412 1983);
PAINT GREEN (-412 1983);
FORCEPROP 2 LAST CDS_LIB standard
J 0
(-350 1975);
PAINT MONO (-350 1975);
DISPLAY INVISIBLE (-350 1975);
FORCEPROP 1 LAST BODY_TYPE PLUMBING
J 0
(-350 2025);
DISPLAY 0.872340 (-350 2025);
PAINT GREEN (-350 2025);
DISPLAY INVISIBLE (-350 2025);
FORCEPROP 1 LAST HDL_TAP TRUE
J 0
(-25 1850);
DISPLAY 0.872340 (-25 1850);
DISPLAY INVISIBLE (-25 1850);
FORCEPROP 1 LAST PATH I86
J 0
(-352 1975);
DISPLAY 0.872340 (-352 1975);
PAINT GREEN (-352 1975);
DISPLAY INVISIBLE (-352 1975);
FORCEADD TAP..1
(-350 2075);
FORCEPROP 3 LASTPIN (-400 2075) SIG_NAME M_H_CPU0_SB_DQ<22>
J 0
(-390 2085);
DISPLAY 0.659574 (-390 2085);
PAINT MONO (-390 2085);
DISPLAY INVISIBLE (-390 2085);
FORCEPROP 1 LASTPIN (-400 2075) BN 22
J 0
(-412 2083);
DISPLAY 0.680851 (-412 2083);
PAINT GREEN (-412 2083);
FORCEPROP 2 LAST CDS_LIB standard
J 0
(-350 2075);
DISPLAY INVISIBLE (-350 2075);
FORCEPROP 1 LAST BODY_TYPE PLUMBING
J 0
(-350 2125);
DISPLAY 0.872340 (-350 2125);
PAINT GREEN (-350 2125);
DISPLAY INVISIBLE (-350 2125);
FORCEPROP 1 LAST HDL_TAP TRUE
J 0
(-25 1950);
DISPLAY 0.872340 (-25 1950);
DISPLAY INVISIBLE (-25 1950);
FORCEPROP 1 LAST PATH I87
J 0
(-352 2075);
DISPLAY 0.872340 (-352 2075);
PAINT GREEN (-352 2075);
DISPLAY INVISIBLE (-352 2075);
FORCEADD TAP..1
(-350 2025);
FORCEPROP 3 LASTPIN (-400 2025) SIG_NAME M_H_CPU0_SB_DQ<21>
J 0
(-390 2035);
DISPLAY 0.659574 (-390 2035);
PAINT MONO (-390 2035);
DISPLAY INVISIBLE (-390 2035);
FORCEPROP 1 LASTPIN (-400 2025) BN 21
J 0
(-412 2033);
DISPLAY 0.680851 (-412 2033);
PAINT GREEN (-412 2033);
FORCEPROP 2 LAST CDS_LIB standard
J 0
(-350 2025);
PAINT MONO (-350 2025);
DISPLAY INVISIBLE (-350 2025);
FORCEPROP 1 LAST BODY_TYPE PLUMBING
J 0
(-350 2075);
DISPLAY 0.872340 (-350 2075);
PAINT GREEN (-350 2075);
DISPLAY INVISIBLE (-350 2075);
FORCEPROP 1 LAST HDL_TAP TRUE
J 0
(-25 1900);
DISPLAY 0.872340 (-25 1900);
DISPLAY INVISIBLE (-25 1900);
FORCEPROP 1 LAST PATH I88
J 0
(-352 2025);
DISPLAY 0.872340 (-352 2025);
PAINT GREEN (-352 2025);
DISPLAY INVISIBLE (-352 2025);
FORCEADD TAP..1
(-350 2125);
FORCEPROP 3 LASTPIN (-400 2125) SIG_NAME M_H_CPU0_SB_DQ<23>
J 0
(-390 2135);
DISPLAY 0.659574 (-390 2135);
PAINT MONO (-390 2135);
DISPLAY INVISIBLE (-390 2135);
FORCEPROP 1 LASTPIN (-400 2125) BN 23
J 0
(-412 2133);
DISPLAY 0.680851 (-412 2133);
PAINT GREEN (-412 2133);
FORCEPROP 2 LAST CDS_LIB standard
J 0
(-350 2125);
DISPLAY INVISIBLE (-350 2125);
FORCEPROP 1 LAST BODY_TYPE PLUMBING
J 0
(-350 2175);
DISPLAY 0.872340 (-350 2175);
PAINT GREEN (-350 2175);
DISPLAY INVISIBLE (-350 2175);
FORCEPROP 1 LAST HDL_TAP TRUE
J 0
(-25 2000);
DISPLAY 0.872340 (-25 2000);
DISPLAY INVISIBLE (-25 2000);
FORCEPROP 1 LAST PATH I89
J 0
(-352 2125);
DISPLAY 0.872340 (-352 2125);
PAINT GREEN (-352 2125);
DISPLAY INVISIBLE (-352 2125);
FORCEADD OFFPAGE..1
(-2825 1600);
FORCEPROP 2 LAST $XR7 96 
J 0
(-3347 1564);
DISPLAY 0.638298 (-3347 1564);
PAINT MONO (-3347 1564);
FORCEPROP 2 LAST $XR6 95 
J 0
(-3257 1564);
DISPLAY 0.638298 (-3257 1564);
PAINT MONO (-3257 1564);
FORCEPROP 2 LAST $XR5 94 
J 0
(-3167 1564);
DISPLAY 0.638298 (-3167 1564);
PAINT MONO (-3167 1564);
FORCEPROP 2 LAST $XR4 93 
J 0
(-3077 1564);
DISPLAY 0.638298 (-3077 1564);
PAINT MONO (-3077 1564);
FORCEPROP 2 LAST $XR3 92 
J 0
(-3347 1600);
DISPLAY 0.638298 (-3347 1600);
PAINT MONO (-3347 1600);
FORCEPROP 2 LAST $XR2 91 
J 0
(-3257 1600);
DISPLAY 0.638298 (-3257 1600);
PAINT MONO (-3257 1600);
FORCEPROP 2 LAST $XR1 90 
J 0
(-3167 1600);
DISPLAY 0.638298 (-3167 1600);
PAINT MONO (-3167 1600);
FORCEPROP 2 LAST $XR0 229 
J 0
(-3077 1600);
DISPLAY 0.638298 (-3077 1600);
PAINT MONO (-3077 1600);
FORCEPROP 2 LAST CDS_LIB standard
J 0
(-2825 1600);
PAINT MONO (-2825 1600);
DISPLAY INVISIBLE (-2825 1600);
FORCEPROP 1 LAST OFFPAGE TRUE
J 0
(-2500 1475);
DISPLAY 0.872340 (-2500 1475);
DISPLAY INVISIBLE (-2500 1475);
FORCEPROP 1 LAST COMMENT_BODY TRUE
J 0
(-2700 1500);
DISPLAY 0.872340 (-2700 1500);
PAINT GREEN (-2700 1500);
DISPLAY INVISIBLE (-2700 1500);
FORCEPROP 2 LAST PATH I9
J 0
(-2775 1675);
DISPLAY 1.021277 (-2775 1675);
DISPLAY INVISIBLE (-2775 1675);
FORCEADD TAP..1
(-350 2175);
FORCEPROP 3 LASTPIN (-400 2175) SIG_NAME M_H_CPU0_SB_DQ<24>
J 0
(-390 2185);
DISPLAY 0.659574 (-390 2185);
PAINT MONO (-390 2185);
DISPLAY INVISIBLE (-390 2185);
FORCEPROP 1 LASTPIN (-400 2175) BN 24
J 0
(-412 2183);
DISPLAY 0.680851 (-412 2183);
PAINT GREEN (-412 2183);
FORCEPROP 2 LAST CDS_LIB standard
J 0
(-350 2175);
DISPLAY INVISIBLE (-350 2175);
FORCEPROP 1 LAST BODY_TYPE PLUMBING
J 0
(-350 2225);
DISPLAY 0.872340 (-350 2225);
PAINT GREEN (-350 2225);
DISPLAY INVISIBLE (-350 2225);
FORCEPROP 1 LAST HDL_TAP TRUE
J 0
(-25 2050);
DISPLAY 0.872340 (-25 2050);
DISPLAY INVISIBLE (-25 2050);
FORCEPROP 1 LAST PATH I90
J 0
(-352 2175);
DISPLAY 0.872340 (-352 2175);
PAINT GREEN (-352 2175);
DISPLAY INVISIBLE (-352 2175);
FORCEADD TAP..1
(-350 2225);
FORCEPROP 3 LASTPIN (-400 2225) SIG_NAME M_H_CPU0_SB_DQ<25>
J 0
(-390 2235);
DISPLAY 0.659574 (-390 2235);
PAINT MONO (-390 2235);
DISPLAY INVISIBLE (-390 2235);
FORCEPROP 1 LASTPIN (-400 2225) BN 25
J 0
(-412 2233);
DISPLAY 0.680851 (-412 2233);
PAINT GREEN (-412 2233);
FORCEPROP 2 LAST CDS_LIB standard
J 0
(-350 2225);
DISPLAY INVISIBLE (-350 2225);
FORCEPROP 1 LAST BODY_TYPE PLUMBING
J 0
(-350 2275);
DISPLAY 0.872340 (-350 2275);
PAINT GREEN (-350 2275);
DISPLAY INVISIBLE (-350 2275);
FORCEPROP 1 LAST HDL_TAP TRUE
J 0
(-25 2100);
DISPLAY 0.872340 (-25 2100);
DISPLAY INVISIBLE (-25 2100);
FORCEPROP 1 LAST PATH I91
J 0
(-352 2225);
DISPLAY 0.872340 (-352 2225);
PAINT GREEN (-352 2225);
DISPLAY INVISIBLE (-352 2225);
FORCEADD TAP..1
(-350 2275);
FORCEPROP 3 LASTPIN (-400 2275) SIG_NAME M_H_CPU0_SB_DQ<26>
J 0
(-390 2285);
DISPLAY 0.659574 (-390 2285);
PAINT MONO (-390 2285);
DISPLAY INVISIBLE (-390 2285);
FORCEPROP 1 LASTPIN (-400 2275) BN 26
J 0
(-412 2283);
DISPLAY 0.680851 (-412 2283);
PAINT GREEN (-412 2283);
FORCEPROP 2 LAST CDS_LIB standard
J 0
(-350 2275);
DISPLAY INVISIBLE (-350 2275);
FORCEPROP 1 LAST BODY_TYPE PLUMBING
J 0
(-350 2325);
DISPLAY 0.872340 (-350 2325);
PAINT GREEN (-350 2325);
DISPLAY INVISIBLE (-350 2325);
FORCEPROP 1 LAST HDL_TAP TRUE
J 0
(-25 2150);
DISPLAY 0.872340 (-25 2150);
DISPLAY INVISIBLE (-25 2150);
FORCEPROP 1 LAST PATH I92
J 0
(-352 2275);
DISPLAY 0.872340 (-352 2275);
PAINT GREEN (-352 2275);
DISPLAY INVISIBLE (-352 2275);
FORCEADD TAP..1
(-350 2375);
FORCEPROP 3 LASTPIN (-400 2375) SIG_NAME M_H_CPU0_SB_DQ<28>
J 0
(-390 2385);
DISPLAY 0.659574 (-390 2385);
PAINT MONO (-390 2385);
DISPLAY INVISIBLE (-390 2385);
FORCEPROP 1 LASTPIN (-400 2375) BN 28
J 0
(-412 2383);
DISPLAY 0.680851 (-412 2383);
PAINT GREEN (-412 2383);
FORCEPROP 2 LAST CDS_LIB standard
J 0
(-350 2375);
DISPLAY INVISIBLE (-350 2375);
FORCEPROP 1 LAST BODY_TYPE PLUMBING
J 0
(-350 2425);
DISPLAY 0.872340 (-350 2425);
PAINT GREEN (-350 2425);
DISPLAY INVISIBLE (-350 2425);
FORCEPROP 1 LAST HDL_TAP TRUE
J 0
(-25 2250);
DISPLAY 0.872340 (-25 2250);
DISPLAY INVISIBLE (-25 2250);
FORCEPROP 1 LAST PATH I93
J 0
(-352 2375);
DISPLAY 0.872340 (-352 2375);
PAINT GREEN (-352 2375);
DISPLAY INVISIBLE (-352 2375);
FORCEADD TAP..1
(-350 2325);
FORCEPROP 3 LASTPIN (-400 2325) SIG_NAME M_H_CPU0_SB_DQ<27>
J 0
(-390 2335);
DISPLAY 0.659574 (-390 2335);
PAINT MONO (-390 2335);
DISPLAY INVISIBLE (-390 2335);
FORCEPROP 1 LASTPIN (-400 2325) BN 27
J 0
(-412 2333);
DISPLAY 0.680851 (-412 2333);
PAINT GREEN (-412 2333);
FORCEPROP 2 LAST CDS_LIB standard
J 0
(-350 2325);
DISPLAY INVISIBLE (-350 2325);
FORCEPROP 1 LAST BODY_TYPE PLUMBING
J 0
(-350 2375);
DISPLAY 0.872340 (-350 2375);
PAINT GREEN (-350 2375);
DISPLAY INVISIBLE (-350 2375);
FORCEPROP 1 LAST HDL_TAP TRUE
J 0
(-25 2200);
DISPLAY 0.872340 (-25 2200);
DISPLAY INVISIBLE (-25 2200);
FORCEPROP 1 LAST PATH I94
J 0
(-352 2325);
DISPLAY 0.872340 (-352 2325);
PAINT GREEN (-352 2325);
DISPLAY INVISIBLE (-352 2325);
FORCEADD TAP..1
(-350 2425);
FORCEPROP 3 LASTPIN (-400 2425) SIG_NAME M_H_CPU0_SB_DQ<29>
J 0
(-390 2435);
DISPLAY 0.659574 (-390 2435);
PAINT MONO (-390 2435);
DISPLAY INVISIBLE (-390 2435);
FORCEPROP 1 LASTPIN (-400 2425) BN 29
J 0
(-412 2433);
DISPLAY 0.680851 (-412 2433);
PAINT GREEN (-412 2433);
FORCEPROP 2 LAST CDS_LIB standard
J 0
(-350 2425);
DISPLAY INVISIBLE (-350 2425);
FORCEPROP 1 LAST BODY_TYPE PLUMBING
J 0
(-350 2475);
DISPLAY 0.872340 (-350 2475);
PAINT GREEN (-350 2475);
DISPLAY INVISIBLE (-350 2475);
FORCEPROP 1 LAST HDL_TAP TRUE
J 0
(-25 2300);
DISPLAY 0.872340 (-25 2300);
DISPLAY INVISIBLE (-25 2300);
FORCEPROP 1 LAST PATH I95
J 0
(-352 2425);
DISPLAY 0.872340 (-352 2425);
PAINT GREEN (-352 2425);
DISPLAY INVISIBLE (-352 2425);
FORCEADD TAP..1
(-350 2475);
FORCEPROP 3 LASTPIN (-400 2475) SIG_NAME M_H_CPU0_SB_DQ<30>
J 0
(-390 2485);
DISPLAY 0.659574 (-390 2485);
PAINT MONO (-390 2485);
DISPLAY INVISIBLE (-390 2485);
FORCEPROP 1 LASTPIN (-400 2475) BN 30
J 0
(-412 2483);
DISPLAY 0.680851 (-412 2483);
PAINT GREEN (-412 2483);
FORCEPROP 2 LAST CDS_LIB standard
J 0
(-350 2475);
DISPLAY INVISIBLE (-350 2475);
FORCEPROP 1 LAST BODY_TYPE PLUMBING
J 0
(-350 2525);
DISPLAY 0.872340 (-350 2525);
PAINT GREEN (-350 2525);
DISPLAY INVISIBLE (-350 2525);
FORCEPROP 1 LAST HDL_TAP TRUE
J 0
(-25 2350);
DISPLAY 0.872340 (-25 2350);
DISPLAY INVISIBLE (-25 2350);
FORCEPROP 1 LAST PATH I96
J 0
(-352 2475);
DISPLAY 0.872340 (-352 2475);
PAINT GREEN (-352 2475);
DISPLAY INVISIBLE (-352 2475);
FORCEADD TAP..1
(-350 2625);
FORCEPROP 3 LASTPIN (-400 2625) SIG_NAME M_H_CPU0_SA_DQ<0>
J 0
(-390 2635);
DISPLAY 0.659574 (-390 2635);
PAINT MONO (-390 2635);
DISPLAY INVISIBLE (-390 2635);
FORCEPROP 1 LASTPIN (-400 2625) BN 0
J 0
(-412 2633);
DISPLAY 0.680851 (-412 2633);
PAINT GREEN (-412 2633);
FORCEPROP 2 LAST CDS_LIB standard
J 0
(-350 2625);
PAINT MONO (-350 2625);
DISPLAY INVISIBLE (-350 2625);
FORCEPROP 1 LAST BODY_TYPE PLUMBING
J 0
(-350 2675);
DISPLAY 0.872340 (-350 2675);
PAINT GREEN (-350 2675);
DISPLAY INVISIBLE (-350 2675);
FORCEPROP 1 LAST HDL_TAP TRUE
J 0
(-25 2500);
DISPLAY 0.872340 (-25 2500);
DISPLAY INVISIBLE (-25 2500);
FORCEPROP 1 LAST PATH I97
J 0
(-352 2625);
DISPLAY 0.872340 (-352 2625);
PAINT GREEN (-352 2625);
DISPLAY INVISIBLE (-352 2625);
FORCEADD TAP..1
(-350 2525);
FORCEPROP 3 LASTPIN (-400 2525) SIG_NAME M_H_CPU0_SB_DQ<31>
J 0
(-390 2535);
DISPLAY 0.659574 (-390 2535);
PAINT MONO (-390 2535);
DISPLAY INVISIBLE (-390 2535);
FORCEPROP 1 LASTPIN (-400 2525) BN 31
J 0
(-412 2533);
DISPLAY 0.680851 (-412 2533);
PAINT GREEN (-412 2533);
FORCEPROP 2 LAST CDS_LIB standard
J 0
(-350 2525);
DISPLAY INVISIBLE (-350 2525);
FORCEPROP 1 LAST BODY_TYPE PLUMBING
J 0
(-350 2575);
DISPLAY 0.872340 (-350 2575);
PAINT GREEN (-350 2575);
DISPLAY INVISIBLE (-350 2575);
FORCEPROP 1 LAST HDL_TAP TRUE
J 0
(-25 2400);
DISPLAY 0.872340 (-25 2400);
DISPLAY INVISIBLE (-25 2400);
FORCEPROP 1 LAST PATH I98
J 0
(-352 2525);
DISPLAY 0.872340 (-352 2525);
PAINT GREEN (-352 2525);
DISPLAY INVISIBLE (-352 2525);
FORCEADD TAP..1
(-350 2725);
FORCEPROP 3 LASTPIN (-400 2725) SIG_NAME M_H_CPU0_SA_DQ<2>
J 0
(-390 2735);
DISPLAY 0.659574 (-390 2735);
PAINT MONO (-390 2735);
DISPLAY INVISIBLE (-390 2735);
FORCEPROP 1 LASTPIN (-400 2725) BN 2
J 0
(-412 2733);
DISPLAY 0.680851 (-412 2733);
PAINT GREEN (-412 2733);
FORCEPROP 2 LAST CDS_LIB standard
J 0
(-350 2725);
PAINT MONO (-350 2725);
DISPLAY INVISIBLE (-350 2725);
FORCEPROP 1 LAST BODY_TYPE PLUMBING
J 0
(-350 2775);
DISPLAY 0.872340 (-350 2775);
PAINT GREEN (-350 2775);
DISPLAY INVISIBLE (-350 2775);
FORCEPROP 1 LAST HDL_TAP TRUE
J 0
(-25 2600);
DISPLAY 0.872340 (-25 2600);
DISPLAY INVISIBLE (-25 2600);
FORCEPROP 1 LAST PATH I99
J 0
(-352 2725);
DISPLAY 0.872340 (-352 2725);
PAINT GREEN (-352 2725);
DISPLAY INVISIBLE (-352 2725);
FORCEADD CAD_NOTE..1
(1500 -275);
FORCEPROP 0 LAST S1 PLACE THE BYPASS CAPS CLOSE TO DIMM
J 0
(1375 -400);
DISPLAY 1.021277 (1375 -400);
PAINT WHITE (1375 -400);
FORCEPROP 2 LAST CDS_LIB logical_power
J 0
(1500 -275);
PAINT MONO (1500 -275);
DISPLAY INVISIBLE (1500 -275);
FORCEPROP 1 LAST COMMENT_BODY TRUE
J 0
(1525 -175);
DISPLAY 0.978723 (1525 -175);
DISPLAY INVISIBLE (1525 -175);
FORCEADD QUANTA_TITLE_BLOCK_C..1
(5975 -1575);
FORCEPROP 0 LAST CDS_CON_LAST_MODIFIED Fri Aug 25 14:01:17 2023
J 0
(4090 -1560);
PAINT MONO (4090 -1560);
DISPLAY INVISIBLE (4090 -1560);
FORCEPROP 1 LAST CUSTOM_TXT_CDS <CON_LAST_MODIFIED>
J 0
(4090 -1560);
DISPLAY 0.978723 (4090 -1560);
FORCEPROP 2 LAST CUSTOM_TXT_CDS <XR_PAGE_TITLE>
J 0
(-1915 3675);
DISPLAY 0.638298 (-1915 3675);
PAINT PINK (-1915 3675);
DISPLAY INVISIBLE (-1915 3675);
FORCEPROP 2 LAST CUSTOM_TXT_CDS <Q_NUMBER>
J 0
(4572 -1472);
DISPLAY 1.212766 (4572 -1472);
FORCEPROP 1 LAST CUSTOM_TXT_CDS <NAME_2>
J 0
(2800 -1525);
FORCEPROP 1 LAST CUSTOM_TXT_CDS <NAME_1>
J 0
(2800 -1400);
FORCEPROP 1 LAST CUSTOM_TXT_CDS <Q_PROJ>
J 0
(3593 -1473);
DISPLAY 1.212766 (3593 -1473);
FORCEPROP 1 LAST CUSTOM_TXT_CDS <Q_REV>
J 0
(5791 -1472);
DISPLAY 1.212766 (5791 -1472);
FORCEPROP 1 LAST CUSTOM_TXT_CDS <CON_PAGE_NUM> OF <CON_TOTAL_PAGES>
J 0
(5529 -1557);
DISPLAY 0.978723 (5529 -1557);
FORCEPROP 1 LAST Q_TITLE DDR5 - CPU0 CHH DIMM2(BLACK)
J 0
(-3391 -1549);
DISPLAY 2.446809 (-3391 -1549);
PAINT GREEN (-3391 -1549);
FORCEPROP 1 LAST Q_DEPT 
J 1
(2212 -1526);
DISPLAY 1.957447 (2212 -1526);
PAINT GREEN (2212 -1526);
FORCEPROP 1 LAST COMMENT_BODY TRUE
J 0
(5987 -1588);
DISPLAY 0.978723 (5987 -1588);
PAINT GREEN (5987 -1588);
DISPLAY INVISIBLE (5987 -1588);
FORCEPROP 2 LAST CDS_XR_PAGE_TITLE CR-97 : @S9S_MB_2U_LIB.S9S_MB_2U(SCH_1):PAGE97
J 0
(-1915 3675);
DISPLAY 0.638298 (-1915 3675);
PAINT PINK (-1915 3675);
DISPLAY INVISIBLE (-1915 3675);
FORCEPROP 2 LAST CDS_LIB pure_quanta
J 0
(5975 -1575);
PAINT MONO (5975 -1575);
DISPLAY INVISIBLE (5975 -1575);
FORCEPROP 1 LAST CDS_LMAN_SYM_OUTLINE -9475,6775,100,-125
J 0
(5975 -1575);
DISPLAY 0.468085 (5975 -1575);
PAINT GREEN (5975 -1575);
DISPLAY INVISIBLE (5975 -1575);
FORCEPROP 2 LAST PAGE_BORDER TRUE
J 0
(-1915 3675);
DISPLAY 0.638298 (-1915 3675);
PAINT PINK (-1915 3675);
DISPLAY INVISIBLE (-1915 3675);
WIRE 17 -1 (-300 1000)(-300 1050);
WIRE 17 -1 (-300 1050)(-300 1100);
WIRE 17 -1 (-300 1100)(-300 1150);
WIRE 17 -1 (-300 1150)(-300 1200);
WIRE 17 -1 (-300 1200)(-300 1250);
WIRE 17 -1 (-300 1250)(-300 1300);
WIRE 17 -1 (-300 1300)(-300 1350);
WIRE 17 -1 (-300 1350)(-300 1400);
WIRE 17 -1 (-300 1400)(-300 1450);
WIRE 17 -1 (-300 1450)(-300 1500);
WIRE 17 -1 (-300 1500)(-300 1550);
WIRE 17 -1 (-300 1550)(-300 1600);
WIRE 17 -1 (-300 1600)(-300 1650);
WIRE 17 -1 (-300 1650)(-300 1700);
WIRE 17 -1 (-300 1700)(-300 1750);
WIRE 17 -1 (-300 1750)(-300 1800);
WIRE 17 -1 (-300 1800)(-300 1850);
WIRE 17 -1 (-300 1850)(-300 1900);
WIRE 17 -1 (-300 1900)(-300 1950);
WIRE 17 -1 (-300 1950)(-300 2000);
WIRE 17 -1 (-300 2000)(-300 2050);
WIRE 17 -1 (-300 2050)(-300 2100);
WIRE 17 -1 (-300 2100)(-300 2150);
WIRE 17 -1 (-300 2150)(-300 2200);
WIRE 17 -1 (-300 2200)(-300 2250);
WIRE 17 -1 (-300 2250)(-300 2300);
WIRE 17 -1 (-300 2300)(-300 2350);
WIRE 17 -1 (-300 2350)(-300 2400);
WIRE 17 -1 (-300 2400)(-300 2450);
WIRE 17 -1 (-300 2450)(-300 2500);
WIRE 17 -1 (-300 2500)(-300 2550);
WIRE 17 -1 (-300 2550)(425 2550);
FORCEPROP 2 LAST SIG_NAME M_H_CPU0_SB_DQ<31:0>
J 0
(-235 2560);
DISPLAY 0.680851 (-235 2560);
PAINT WHITE (-235 2560);
WIRE 17 -1 (-300 2650)(-300 2700);
WIRE 17 -1 (-300 2700)(-300 2750);
WIRE 17 -1 (-300 2750)(-300 2800);
WIRE 17 -1 (-300 2800)(-300 2850);
WIRE 17 -1 (-300 2850)(-300 2900);
WIRE 17 -1 (-300 2900)(-300 2950);
WIRE 17 -1 (-300 2950)(-300 3000);
WIRE 17 -1 (-300 3000)(-300 3050);
WIRE 17 -1 (-300 3050)(-300 3100);
WIRE 17 -1 (-300 3100)(-300 3150);
WIRE 17 -1 (-300 3150)(-300 3200);
WIRE 17 -1 (-300 3200)(-300 3250);
WIRE 17 -1 (-300 3250)(-300 3300);
WIRE 17 -1 (-300 3300)(-300 3350);
WIRE 17 -1 (-300 3350)(-300 3400);
WIRE 17 -1 (-300 3400)(-300 3450);
WIRE 17 -1 (-300 3450)(-300 3500);
WIRE 17 -1 (-300 3500)(-300 3550);
WIRE 17 -1 (-300 3550)(-300 3600);
WIRE 17 -1 (-300 3600)(-300 3650);
WIRE 17 -1 (-300 3650)(-300 3700);
WIRE 17 -1 (-300 3700)(-300 3750);
WIRE 17 -1 (-300 3750)(-300 3800);
WIRE 17 -1 (-300 3800)(-300 3850);
WIRE 17 -1 (-300 3850)(-300 3900);
WIRE 17 -1 (-300 3900)(-300 3950);
WIRE 17 -1 (-300 3950)(-300 4000);
WIRE 17 -1 (-300 4000)(-300 4050);
WIRE 17 -1 (-300 4050)(-300 4100);
WIRE 17 -1 (-300 4100)(-300 4150);
WIRE 17 -1 (-300 4150)(-300 4200);
WIRE 17 -1 (-300 4200)(425 4200);
FORCEPROP 2 LAST SIG_NAME M_H_CPU0_SA_DQ<31:0>
J 0
(-235 4210);
DISPLAY 0.680851 (-235 4210);
PAINT WHITE (-235 4210);
WIRE 17 -1 (-2050 2250)(-2050 2300);
WIRE 17 -1 (-2050 2200)(-2050 2250);
WIRE 17 -1 (-2050 2300)(-2050 2350);
WIRE 17 -1 (-2875 2350)(-2050 2350);
FORCEPROP 2 LAST SIG_NAME M_H_CPU0_SB_CB<7:0>
J 0
(-2785 2360);
DISPLAY 0.680851 (-2785 2360);
PAINT WHITE (-2785 2360);
WIRE 17 -1 (-2050 2550)(-2050 2600);
WIRE 17 -1 (-2050 2500)(-2050 2550);
WIRE 17 -1 (-2050 2600)(-2050 2650);
WIRE 17 -1 (-2050 2650)(-2050 2700);
WIRE 17 -1 (-2050 2450)(-2050 2500);
WIRE 17 -1 (-2050 2700)(-2050 2750);
WIRE 17 -1 (-2050 2750)(-2050 2800);
WIRE 17 -1 (-2875 2800)(-2050 2800);
FORCEPROP 2 LAST SIG_NAME M_H_CPU0_SA_CB<7:0>
J 0
(-2785 2810);
DISPLAY 0.680851 (-2785 2810);
PAINT WHITE (-2785 2810);
WIRE 17 -1 (-2875 3800)(-2050 3800);
FORCEPROP 2 LAST SIG_NAME M_H_CPU0_SB_CA<6:0>
J 0
(-2785 3810);
DISPLAY 0.680851 (-2785 3810);
PAINT WHITE (-2785 3810);
WIRE 17 -1 (-2875 4200)(-2050 4200);
FORCEPROP 2 LAST SIG_NAME M_H_CPU0_SA_CA<6:0>
J 0
(-2785 4210);
DISPLAY 0.680851 (-2785 4210);
PAINT WHITE (-2785 4210);
WIRE 17 -1 (-2050 3750)(-2050 3800);
WIRE 17 -1 (-2050 3700)(-2050 3750);
WIRE 17 -1 (-2050 4150)(-2050 4200);
WIRE 17 -1 (-2050 4100)(-2050 4150);
WIRE 17 -1 (-2050 3650)(-2050 3700);
WIRE 17 -1 (-2050 4050)(-2050 4100);
WIRE 17 -1 (-2050 3600)(-2050 3650);
WIRE 17 -1 (-2050 3550)(-2050 3600);
WIRE 17 -1 (-2050 3500)(-2050 3550);
WIRE 17 -1 (-2050 4000)(-2050 4050);
WIRE 17 -1 (-2050 3950)(-2050 4000);
WIRE 17 -1 (-2050 3900)(-2050 3950);
WIRE 17 -1 (2450 2250)(2450 2350);
WIRE 17 -1 (2450 2350)(2450 2450);
WIRE 17 -1 (2450 2450)(2450 2550);
WIRE 17 -1 (2450 2650)(2450 2550);
WIRE 17 -1 (2450 2650)(2450 2750);
WIRE 17 -1 (2450 2750)(2450 2850);
WIRE 17 -1 (2450 2850)(2450 2950);
WIRE 17 -1 (2450 2950)(2450 3050);
WIRE 17 -1 (2450 3050)(2450 3150);
WIRE 17 -1 (2450 3150)(3475 3150);
FORCEPROP 2 LAST SIG_NAME M_H_CPU0_SB_DQS_DP<9:0>
J 0
(2690 3160);
DISPLAY 0.680851 (2690 3160);
PAINT WHITE (2690 3160);
WIRE 17 -1 (2450 3300)(2450 3400);
WIRE 17 -1 (2450 3400)(2450 3500);
WIRE 17 -1 (2450 3500)(2450 3600);
WIRE 17 -1 (2450 3700)(2450 3600);
WIRE 17 -1 (2450 3700)(2450 3800);
WIRE 17 -1 (2450 3800)(2450 3900);
WIRE 17 -1 (2450 3900)(2450 4000);
WIRE 17 -1 (2450 4000)(2450 4100);
WIRE 17 -1 (2450 4100)(2450 4200);
WIRE 17 -1 (2450 4200)(3475 4200);
FORCEPROP 2 LAST SIG_NAME M_H_CPU0_SA_DQS_DP<9:0>
J 0
(2690 4210);
DISPLAY 0.680851 (2690 4210);
PAINT WHITE (2690 4210);
WIRE 17 -1 (2625 2300)(2625 2400);
WIRE 17 -1 (2625 2200)(2625 2300);
WIRE 17 -1 (2625 2400)(2625 2500);
WIRE 17 -1 (2625 2600)(2625 2500);
WIRE 17 -1 (2625 2600)(2625 2700);
WIRE 17 -1 (2625 2700)(2625 2800);
WIRE 17 -1 (2625 2800)(2625 2900);
WIRE 17 -1 (2625 2900)(2625 3000);
WIRE 17 -1 (2625 3000)(2625 3100);
WIRE 17 -1 (2625 3100)(3475 3100);
FORCEPROP 2 LAST SIG_NAME M_H_CPU0_SB_DQS_DN<9:0>
J 0
(2690 3110);
DISPLAY 0.680851 (2690 3110);
PAINT WHITE (2690 3110);
WIRE 17 -1 (2625 3350)(2625 3450);
WIRE 17 -1 (2625 3250)(2625 3350);
WIRE 17 -1 (2625 3450)(2625 3550);
WIRE 17 -1 (2625 3650)(2625 3550);
WIRE 17 -1 (2625 3650)(2625 3750);
WIRE 17 -1 (2625 3750)(2625 3850);
WIRE 17 -1 (2625 3850)(2625 3950);
WIRE 17 -1 (2625 3950)(2625 4050);
WIRE 17 -1 (2625 4050)(2625 4150);
WIRE 17 -1 (2625 4150)(3475 4150);
FORCEPROP 2 LAST SIG_NAME M_H_CPU0_SA_DQS_DN<9:0>
J 0
(2690 4160);
DISPLAY 0.680851 (2690 4160);
PAINT WHITE (2690 4160);
WIRE 17 -1 (-2050 2150)(-2050 2200);
WIRE 17 -1 (-2050 2100)(-2050 2150);
WIRE 17 -1 (-2050 2050)(-2050 2100);
WIRE 17 -1 (-2050 2000)(-2050 2050);
WIRE 16 -1 (2375 575)(2375 525);
WIRE 16 -1 (-2825 2000)(-2825 1700);
WIRE 16 -1 (1375 400)(1375 575);
WIRE 16 -1 (4075 4675)(4075 4175);
WIRE 16 -1 (5775 825)(5775 525);
WIRE 16 -1 (5775 875)(5775 825);
WIRE 16 -1 (5525 825)(5775 825);
WIRE 16 -1 (4075 525)(4075 925);
WIRE 16 -1 (3000 -25)(3000 50);
WIRE 16 -1 (1375 200)(1375 -25);
WIRE 16 -1 (-1775 -150)(-1775 -75);
WIRE 16 3135 (1025 800)(1025 -500);
WIRE 16 3135 (3625 800)(1025 800);
WIRE 16 3135 (1025 -500)(3625 -500);
WIRE 16 3135 (3625 -500)(3625 800);
WIRE 16 -1 (-2825 1700)(-1775 1700);
WIRE 16 -1 (-1775 1800)(-2875 1800);
FORCEPROP 2 LAST SIG_NAME M_H_CPU0_ALERT_N
J 0
(-2787 1809);
DISPLAY 0.680851 (-2787 1809);
PAINT WHITE (-2787 1809);
WIRE 16 -1 (-1775 1650)(-2775 1650);
FORCEPROP 2 LAST SIG_NAME PD_CHH_CPU0_DIMM2_SAA
J 0
(-2785 1660);
DISPLAY 0.680851 (-2785 1660);
PAINT WHITE (-2785 1660);
WIRE 16 -1 (-1775 1600)(-2775 1600);
FORCEPROP 2 LAST SIG_NAME I3C_SPD_DDREFGH_CPU0_LVC1_SDA
J 0
(-2785 1610);
DISPLAY 0.680851 (-2785 1610);
PAINT WHITE (-2785 1610);
WIRE 16 -1 (-2150 1900)(-2875 1900);
FORCEPROP 2 LAST SIG_NAME RST_M_GH_CPU0_FPGA_N
J 0
(-2787 1909);
DISPLAY 0.680851 (-2787 1909);
PAINT WHITE (-2787 1909);
WIRE 16 -1 (-2150 1900)(-2150 1850);
WIRE 16 -1 (-2150 1850)(-1775 1850);
WIRE 16 -1 (-3275 1450)(-3075 1450);
WIRE 16 -1 (-3275 1550)(-3275 1450);
WIRE 16 -1 (-1775 1550)(-3275 1550);
FORCEPROP 2 LAST SIG_NAME I3C_SPD_DDREFGH_CPU0_LVC1_SCL_R8
J 0
(-2835 1560);
DISPLAY 0.680851 (-2835 1560);
PAINT WHITE (-2835 1560);
WIRE 16 -1 (-1675 1400)(-1725 1400);
WIRE 16 -1 (-1675 1450)(-1675 1400);
WIRE 16 -1 (-2875 1450)(-1675 1450);
FORCEPROP 2 LAST SIG_NAME I3C_SPD_DDREFGH_CPU0_LVC1_SCL
J 0
(-2710 1460);
DISPLAY 0.680851 (-2710 1460);
PAINT WHITE (-2710 1460);
WIRE 16 -1 (-1775 1300)(-2875 1300);
FORCEPROP 2 LAST SIG_NAME PWRGD_CHH_CPU0_DIMM2
J 0
(-2787 1309);
DISPLAY 0.680851 (-2787 1309);
PAINT WHITE (-2787 1309);
WIRE 16 -1 (-1950 1950)(-1950 1975);
WIRE 16 -1 (-1950 1950)(-1775 1950);
WIRE 16 -1 (-1950 2000)(-1950 2025);
WIRE 16 -1 (-1950 2000)(-1775 2000);
WIRE 16 -1 (-1950 2050)(-1950 2075);
WIRE 16 -1 (-1950 2050)(-1775 2050);
WIRE 16 -1 (-1775 1200)(-2875 1200);
FORCEPROP 2 LAST SIG_NAME TP_CHH_CPU0_DIMM2_FRU_6
J 0
(-2787 1209);
DISPLAY 0.680851 (-2787 1209);
PAINT WHITE (-2787 1209);
WIRE 16 -1 (-1950 2100)(-1950 2125);
WIRE 16 -1 (-1950 2100)(-1775 2100);
WIRE 16 -1 (-1950 2150)(-1950 2175);
WIRE 16 -1 (-1950 2150)(-1775 2150);
WIRE 16 -1 (-1950 2200)(-1950 2225);
WIRE 16 -1 (-1950 2200)(-1775 2200);
WIRE 16 -1 (-1950 2300)(-1950 2325);
WIRE 16 -1 (-1950 2300)(-1775 2300);
WIRE 16 -1 (-1950 2400)(-1950 2425);
WIRE 16 -1 (-1950 2400)(-1775 2400);
WIRE 16 -1 (-1950 2450)(-1950 2475);
WIRE 16 -1 (-1950 2450)(-1775 2450);
WIRE 16 -1 (-1775 2850)(-2875 2850);
FORCEPROP 2 LAST SIG_NAME M_H_CPU0_CLK_DN<1>
J 0
(-2787 2859);
DISPLAY 0.680851 (-2787 2859);
PAINT WHITE (-2787 2859);
WIRE 16 -1 (-1775 2900)(-2875 2900);
FORCEPROP 2 LAST SIG_NAME M_H_CPU0_CLK_DP<1>
J 0
(-2787 2909);
DISPLAY 0.680851 (-2787 2909);
PAINT WHITE (-2787 2909);
WIRE 16 -1 (2225 2375)(2525 2375);
WIRE 16 -1 (2225 4125)(2525 4125);
WIRE 16 -1 (2225 4025)(2525 4025);
WIRE 16 -1 (2225 3925)(2525 3925);
WIRE 16 -1 (2225 3725)(2525 3725);
WIRE 16 -1 (2225 3825)(2525 3825);
WIRE 16 -1 (2225 3625)(2525 3625);
WIRE 16 -1 (2225 3525)(2525 3525);
WIRE 16 -1 (2225 3425)(2525 3425);
WIRE 16 -1 (2225 3225)(2525 3225);
WIRE 16 -1 (2225 3325)(2525 3325);
WIRE 16 -1 (2225 3075)(2525 3075);
WIRE 16 -1 (2225 2975)(2525 2975);
WIRE 16 -1 (2225 2875)(2525 2875);
WIRE 16 -1 (2225 2775)(2525 2775);
WIRE 16 -1 (2225 2575)(2525 2575);
WIRE 16 -1 (2225 2675)(2525 2675);
WIRE 16 -1 (2225 2475)(2525 2475);
WIRE 16 -1 (2225 2175)(2525 2175);
WIRE 16 -1 (2225 2275)(2525 2275);
WIRE 16 -1 (2225 4175)(2350 4175);
WIRE 16 -1 (2225 4075)(2350 4075);
WIRE 16 -1 (2225 3975)(2350 3975);
WIRE 16 -1 (2225 3875)(2350 3875);
WIRE 16 -1 (2225 3775)(2350 3775);
WIRE 16 -1 (2225 3675)(2350 3675);
WIRE 16 -1 (2225 3575)(2350 3575);
WIRE 16 -1 (2225 3475)(2350 3475);
WIRE 16 -1 (2225 3375)(2350 3375);
WIRE 16 -1 (2225 3275)(2350 3275);
WIRE 16 -1 (2225 3125)(2350 3125);
WIRE 16 -1 (2225 3025)(2350 3025);
WIRE 16 -1 (2225 2925)(2350 2925);
WIRE 16 -1 (2225 2825)(2350 2825);
WIRE 16 -1 (2225 2725)(2350 2725);
WIRE 16 -1 (2225 2625)(2350 2625);
WIRE 16 -1 (2225 2525)(2350 2525);
WIRE 16 -1 (2225 2425)(2350 2425);
WIRE 16 -1 (2225 2325)(2350 2325);
WIRE 16 -1 (2225 2225)(2350 2225);
WIRE 16 -1 (-1775 900)(-2875 900);
FORCEPROP 2 LAST SIG_NAME TP_CHH_CPU0_DIMM2_FRU_0
J 0
(-2787 909);
DISPLAY 0.680851 (-2787 909);
PAINT WHITE (-2787 909);
WIRE 16 -1 (-1775 750)(-2875 750);
FORCEPROP 2 LAST SIG_NAME M_H_CPU0_SA_RSP<1>
J 0
(-2787 759);
DISPLAY 0.680851 (-2787 759);
PAINT WHITE (-2787 759);
WIRE 16 -1 (-1775 700)(-2875 700);
FORCEPROP 2 LAST SIG_NAME M_H_CPU0_SB_RSP<1>
J 0
(-2787 709);
DISPLAY 0.680851 (-2787 709);
PAINT WHITE (-2787 709);
WIRE 16 -1 (-1775 3000)(-2875 3000);
FORCEPROP 2 LAST SIG_NAME M_H_CPU0_SB_CS_N<2>
J 0
(-2787 3009);
DISPLAY 0.680851 (-2787 3009);
PAINT WHITE (-2787 3009);
WIRE 16 -1 (-1775 3050)(-2875 3050);
FORCEPROP 2 LAST SIG_NAME M_H_CPU0_SB_CS_N<3>
J 0
(-2787 3059);
DISPLAY 0.680851 (-2787 3059);
PAINT WHITE (-2787 3059);
WIRE 16 -1 (-1775 3200)(-2875 3200);
FORCEPROP 2 LAST SIG_NAME M_H_CPU0_SA_CS_N<3>
J 0
(-2787 3209);
DISPLAY 0.680851 (-2787 3209);
PAINT WHITE (-2787 3209);
WIRE 16 -1 (-1775 3300)(-2875 3300);
FORCEPROP 2 LAST SIG_NAME M_H_CPU0_SB_PAR
J 0
(-2787 3309);
DISPLAY 0.680851 (-2787 3309);
PAINT WHITE (-2787 3309);
WIRE 16 -1 (-1775 3350)(-2875 3350);
FORCEPROP 2 LAST SIG_NAME M_H_CPU0_SA_PAR
J 0
(-2787 3359);
DISPLAY 0.680851 (-2787 3359);
PAINT WHITE (-2787 3359);
WIRE 16 -1 (-1775 3150)(-2875 3150);
FORCEPROP 2 LAST SIG_NAME M_H_CPU0_SA_CS_N<2>
J 0
(-2787 3159);
DISPLAY 0.680851 (-2787 3159);
PAINT WHITE (-2787 3159);
WIRE 16 -1 (4325 4075)(4075 4075);
WIRE 16 -1 (4075 4125)(4075 4075);
WIRE 16 -1 (4075 4125)(4325 4125);
WIRE 16 -1 (4075 4175)(4075 4125);
WIRE 16 -1 (4325 4175)(4075 4175);
WIRE 16 -1 (-400 3850)(-400 3875);
WIRE 16 -1 (-575 3850)(-400 3850);
WIRE 16 -1 (-575 3600)(-400 3600);
WIRE 16 -1 (-400 3600)(-400 3625);
WIRE 16 -1 (-575 3550)(-400 3550);
WIRE 16 -1 (-400 3550)(-400 3575);
WIRE 16 -1 (-575 3500)(-400 3500);
WIRE 16 -1 (-400 3500)(-400 3525);
WIRE 16 -1 (-575 3650)(-400 3650);
WIRE 16 -1 (-400 3650)(-400 3675);
WIRE 16 -1 (-400 3350)(-400 3375);
WIRE 16 -1 (-575 3350)(-400 3350);
WIRE 16 -1 (-575 3300)(-400 3300);
WIRE 16 -1 (-400 3300)(-400 3325);
WIRE 16 -1 (-575 3250)(-400 3250);
WIRE 16 -1 (-400 3250)(-400 3275);
WIRE 16 -1 (-575 2650)(-400 2650);
WIRE 16 -1 (-400 2650)(-400 2675);
WIRE 16 -1 (-575 2700)(-400 2700);
WIRE 16 -1 (-400 2700)(-400 2725);
WIRE 16 -1 (-400 4150)(-400 4175);
WIRE 16 -1 (-575 4150)(-400 4150);
WIRE 16 -1 (-1950 2750)(-1950 2775);
WIRE 16 -1 (-1950 2750)(-1775 2750);
WIRE 16 -1 (-1950 2600)(-1950 2625);
WIRE 16 -1 (-1950 2600)(-1775 2600);
WIRE 16 -1 (-1950 3850)(-1950 3875);
WIRE 16 -1 (-1950 3850)(-1775 3850);
WIRE 16 -1 (-1950 3450)(-1950 3475);
WIRE 16 -1 (-1950 3450)(-1775 3450);
WIRE 16 -1 (-1950 3900)(-1950 3925);
WIRE 16 -1 (-1950 3900)(-1775 3900);
WIRE 16 -1 (-1950 3500)(-1950 3525);
WIRE 16 -1 (-1950 3500)(-1775 3500);
WIRE 16 -1 (-1950 3950)(-1950 3975);
WIRE 16 -1 (-1950 3950)(-1775 3950);
WIRE 16 -1 (-1950 3550)(-1950 3575);
WIRE 16 -1 (-1950 3550)(-1775 3550);
WIRE 16 -1 (-1950 4000)(-1950 4025);
WIRE 16 -1 (-1950 4000)(-1775 4000);
WIRE 16 -1 (-1950 3600)(-1950 3625);
WIRE 16 -1 (-1950 3600)(-1775 3600);
WIRE 16 -1 (-1950 4050)(-1950 4075);
WIRE 16 -1 (-1950 4050)(-1775 4050);
WIRE 16 -1 (-1950 3650)(-1950 3675);
WIRE 16 -1 (-1950 3650)(-1775 3650);
WIRE 16 -1 (-1950 4100)(-1950 4125);
WIRE 16 -1 (-1950 4100)(-1775 4100);
WIRE 16 -1 (-1950 3700)(-1950 3725);
WIRE 16 -1 (-1950 3700)(-1775 3700);
WIRE 16 -1 (-1950 4150)(-1950 4175);
WIRE 16 -1 (-1950 4150)(-1775 4150);
WIRE 16 -1 (-1950 3750)(-1950 3775);
WIRE 16 -1 (-1950 3750)(-1775 3750);
WIRE 16 -1 (-1950 2700)(-1950 2725);
WIRE 16 -1 (-1950 2700)(-1775 2700);
WIRE 16 -1 (-1950 2650)(-1950 2675);
WIRE 16 -1 (-1950 2650)(-1775 2650);
WIRE 16 -1 (-1950 2550)(-1775 2550);
WIRE 16 -1 (-1950 2550)(-1950 2575);
WIRE 16 -1 (-1950 2500)(-1950 2525);
WIRE 16 -1 (-1950 2500)(-1775 2500);
WIRE 16 -1 (-1950 2250)(-1950 2275);
WIRE 16 -1 (-1950 2250)(-1775 2250);
WIRE 16 -1 (-400 4100)(-400 4125);
WIRE 16 -1 (-575 4100)(-400 4100);
WIRE 16 -1 (-400 4050)(-400 4075);
WIRE 16 -1 (-575 4050)(-400 4050);
WIRE 16 -1 (-400 4000)(-400 4025);
WIRE 16 -1 (-575 4000)(-400 4000);
WIRE 16 -1 (-400 3950)(-400 3975);
WIRE 16 -1 (-575 3950)(-400 3950);
WIRE 16 -1 (-400 3900)(-400 3925);
WIRE 16 -1 (-575 3900)(-400 3900);
WIRE 16 -1 (-400 3800)(-400 3825);
WIRE 16 -1 (-575 3800)(-400 3800);
WIRE 16 -1 (-400 3750)(-400 3775);
WIRE 16 -1 (-575 3750)(-400 3750);
WIRE 16 -1 (-400 3700)(-400 3725);
WIRE 16 -1 (-575 3700)(-400 3700);
WIRE 16 -1 (-400 3450)(-400 3475);
WIRE 16 -1 (-575 3450)(-400 3450);
WIRE 16 -1 (-400 3400)(-400 3425);
WIRE 16 -1 (-575 3400)(-400 3400);
WIRE 16 -1 (-400 3200)(-400 3225);
WIRE 16 -1 (-575 3200)(-400 3200);
WIRE 16 -1 (-400 3150)(-400 3175);
WIRE 16 -1 (-575 3150)(-400 3150);
WIRE 16 -1 (-400 3100)(-400 3125);
WIRE 16 -1 (-575 3100)(-400 3100);
WIRE 16 -1 (-400 3050)(-400 3075);
WIRE 16 -1 (-575 3050)(-400 3050);
WIRE 16 -1 (-400 3000)(-400 3025);
WIRE 16 -1 (-575 3000)(-400 3000);
WIRE 16 -1 (-400 2950)(-400 2975);
WIRE 16 -1 (-575 2950)(-400 2950);
WIRE 16 -1 (-400 2900)(-400 2925);
WIRE 16 -1 (-575 2900)(-400 2900);
WIRE 16 -1 (-400 2850)(-400 2875);
WIRE 16 -1 (-575 2850)(-400 2850);
WIRE 16 -1 (-400 2800)(-400 2825);
WIRE 16 -1 (-575 2800)(-400 2800);
WIRE 16 -1 (-400 2750)(-400 2775);
WIRE 16 -1 (-575 2750)(-400 2750);
WIRE 16 -1 (-400 2600)(-400 2625);
WIRE 16 -1 (-575 2600)(-400 2600);
WIRE 16 -1 (-400 2500)(-400 2525);
WIRE 16 -1 (-575 2500)(-400 2500);
WIRE 16 -1 (-400 2450)(-400 2475);
WIRE 16 -1 (-575 2450)(-400 2450);
WIRE 16 -1 (-400 2400)(-400 2425);
WIRE 16 -1 (-575 2400)(-400 2400);
WIRE 16 -1 (-400 2350)(-400 2375);
WIRE 16 -1 (-575 2350)(-400 2350);
WIRE 16 -1 (-400 2300)(-400 2325);
WIRE 16 -1 (-575 2300)(-400 2300);
WIRE 16 -1 (-400 2250)(-400 2275);
WIRE 16 -1 (-575 2250)(-400 2250);
WIRE 16 -1 (-400 2200)(-400 2225);
WIRE 16 -1 (-575 2200)(-400 2200);
WIRE 16 -1 (-400 2150)(-400 2175);
WIRE 16 -1 (-575 2150)(-400 2150);
WIRE 16 -1 (-400 2100)(-400 2125);
WIRE 16 -1 (-575 2100)(-400 2100);
WIRE 16 -1 (-400 2050)(-400 2075);
WIRE 16 -1 (-575 2050)(-400 2050);
WIRE 16 -1 (-400 2000)(-400 2025);
WIRE 16 -1 (-575 2000)(-400 2000);
WIRE 16 -1 (-400 1950)(-400 1975);
WIRE 16 -1 (-575 1950)(-400 1950);
WIRE 16 -1 (-400 1900)(-400 1925);
WIRE 16 -1 (-575 1900)(-400 1900);
WIRE 16 -1 (-400 1850)(-400 1875);
WIRE 16 -1 (-575 1850)(-400 1850);
WIRE 16 -1 (-400 1800)(-400 1825);
WIRE 16 -1 (-575 1800)(-400 1800);
WIRE 16 -1 (-400 1750)(-400 1775);
WIRE 16 -1 (-575 1750)(-400 1750);
WIRE 16 -1 (-400 1700)(-400 1725);
WIRE 16 -1 (-575 1700)(-400 1700);
WIRE 16 -1 (-400 1650)(-400 1675);
WIRE 16 -1 (-575 1650)(-400 1650);
WIRE 16 -1 (-400 1600)(-400 1625);
WIRE 16 -1 (-575 1600)(-400 1600);
WIRE 16 -1 (-400 1550)(-400 1575);
WIRE 16 -1 (-575 1550)(-400 1550);
WIRE 16 -1 (-400 1500)(-400 1525);
WIRE 16 -1 (-575 1500)(-400 1500);
WIRE 16 -1 (-400 1450)(-400 1475);
WIRE 16 -1 (-575 1450)(-400 1450);
WIRE 16 -1 (-400 1400)(-400 1425);
WIRE 16 -1 (-575 1400)(-400 1400);
WIRE 16 -1 (-400 1350)(-400 1375);
WIRE 16 -1 (-575 1350)(-400 1350);
WIRE 16 -1 (-400 1300)(-400 1325);
WIRE 16 -1 (-575 1300)(-400 1300);
WIRE 16 -1 (-400 1250)(-400 1275);
WIRE 16 -1 (-575 1250)(-400 1250);
WIRE 16 -1 (-400 1200)(-400 1225);
WIRE 16 -1 (-575 1200)(-400 1200);
WIRE 16 -1 (-400 1150)(-400 1175);
WIRE 16 -1 (-575 1150)(-400 1150);
WIRE 16 -1 (-400 1100)(-400 1125);
WIRE 16 -1 (-575 1100)(-400 1100);
WIRE 16 -1 (-400 1050)(-400 1075);
WIRE 16 -1 (-575 1050)(-400 1050);
WIRE 16 -1 (-400 1000)(-400 1025);
WIRE 16 -1 (-575 1000)(-400 1000);
WIRE 16 -1 (-400 950)(-400 975);
WIRE 16 -1 (-575 950)(-400 950);
WIRE 16 -1 (-1775 1150)(-2875 1150);
FORCEPROP 2 LAST SIG_NAME TP_CHH_CPU0_DIMM2_FRU_5
J 0
(-2787 1159);
DISPLAY 0.680851 (-2787 1159);
PAINT WHITE (-2787 1159);
WIRE 16 -1 (-1775 1100)(-2875 1100);
FORCEPROP 2 LAST SIG_NAME TP_CHH_CPU0_DIMM2_FRU_4
J 0
(-2787 1109);
DISPLAY 0.680851 (-2787 1109);
PAINT WHITE (-2787 1109);
WIRE 16 -1 (-1775 1050)(-2875 1050);
FORCEPROP 2 LAST SIG_NAME TP_CHH_CPU0_DIMM2_FRU_3
J 0
(-2787 1059);
DISPLAY 0.680851 (-2787 1059);
PAINT WHITE (-2787 1059);
WIRE 16 -1 (-1775 1000)(-2875 1000);
FORCEPROP 2 LAST SIG_NAME TP_CHH_CPU0_DIMM2_FRU_2
J 0
(-2787 1009);
DISPLAY 0.680851 (-2787 1009);
PAINT WHITE (-2787 1009);
WIRE 16 -1 (-1775 950)(-2875 950);
FORCEPROP 2 LAST SIG_NAME TP_CHH_CPU0_DIMM2_FRU_1
J 0
(-2787 959);
DISPLAY 0.680851 (-2787 959);
PAINT WHITE (-2787 959);
WIRE 16 -1 (4075 925)(4325 925);
WIRE 16 -1 (4075 925)(4075 975);
WIRE 16 -1 (4075 975)(4325 975);
WIRE 16 -1 (4075 975)(4075 1025);
WIRE 16 -1 (4075 1025)(4325 1025);
WIRE 16 -1 (4075 1025)(4075 1075);
WIRE 16 -1 (4075 1075)(4325 1075);
WIRE 16 -1 (4075 1075)(4075 1125);
WIRE 16 -1 (4075 1125)(4325 1125);
WIRE 16 -1 (4075 1125)(4075 1175);
WIRE 16 -1 (4075 1175)(4325 1175);
WIRE 16 -1 (4075 1175)(4075 1225);
WIRE 16 -1 (4075 1225)(4325 1225);
WIRE 16 -1 (4075 1225)(4075 1275);
WIRE 16 -1 (4075 1275)(4325 1275);
WIRE 16 -1 (4075 1275)(4075 1325);
WIRE 16 -1 (4075 1325)(4325 1325);
WIRE 16 -1 (4075 1325)(4075 1375);
WIRE 16 -1 (4075 1375)(4325 1375);
WIRE 16 -1 (4075 1375)(4075 1425);
WIRE 16 -1 (4325 1425)(4075 1425);
WIRE 16 -1 (4075 1425)(4075 1475);
WIRE 16 -1 (4075 1475)(4325 1475);
WIRE 16 -1 (4075 1475)(4075 1525);
WIRE 16 -1 (4075 1525)(4325 1525);
WIRE 16 -1 (4075 1525)(4075 1575);
WIRE 16 -1 (4075 1575)(4325 1575);
WIRE 16 -1 (4075 1575)(4075 1625);
WIRE 16 -1 (4075 1625)(4325 1625);
WIRE 16 -1 (4075 1625)(4075 1675);
WIRE 16 -1 (4075 1675)(4325 1675);
WIRE 16 -1 (4075 1675)(4075 1725);
WIRE 16 -1 (4075 1725)(4325 1725);
WIRE 16 -1 (4075 1725)(4075 1775);
WIRE 16 -1 (4075 1775)(4325 1775);
WIRE 16 -1 (4075 1775)(4075 1825);
WIRE 16 -1 (4075 1825)(4325 1825);
WIRE 16 -1 (4075 1825)(4075 1875);
WIRE 16 -1 (4075 1875)(4325 1875);
WIRE 16 -1 (4075 1875)(4075 1925);
WIRE 16 -1 (4325 1925)(4075 1925);
WIRE 16 -1 (4075 1925)(4075 1975);
WIRE 16 -1 (4075 1975)(4325 1975);
WIRE 16 -1 (4075 1975)(4075 2025);
WIRE 16 -1 (4075 2025)(4325 2025);
WIRE 16 -1 (4075 2025)(4075 2075);
WIRE 16 -1 (4075 2075)(4325 2075);
WIRE 16 -1 (4075 2075)(4075 2125);
WIRE 16 -1 (4075 2125)(4325 2125);
WIRE 16 -1 (4075 2125)(4075 2175);
WIRE 16 -1 (4075 2175)(4325 2175);
WIRE 16 -1 (4075 2175)(4075 2225);
WIRE 16 -1 (4075 2225)(4325 2225);
WIRE 16 -1 (4075 2225)(4075 2275);
WIRE 16 -1 (4075 2275)(4325 2275);
WIRE 16 -1 (4075 2275)(4075 2325);
WIRE 16 -1 (4075 2325)(4325 2325);
WIRE 16 -1 (4075 2325)(4075 2375);
WIRE 16 -1 (4075 2375)(4325 2375);
WIRE 16 -1 (4075 2375)(4075 2425);
WIRE 16 -1 (4325 2425)(4075 2425);
WIRE 16 -1 (4075 2425)(4075 2475);
WIRE 16 -1 (4075 2475)(4325 2475);
WIRE 16 -1 (4075 2475)(4075 2525);
WIRE 16 -1 (4075 2525)(4325 2525);
WIRE 16 -1 (4075 2525)(4075 2575);
WIRE 16 -1 (4075 2575)(4325 2575);
WIRE 16 -1 (4075 2575)(4075 2625);
WIRE 16 -1 (4075 2625)(4325 2625);
WIRE 16 -1 (4075 2625)(4075 2675);
WIRE 16 -1 (4075 2675)(4325 2675);
WIRE 16 -1 (4075 2675)(4075 2725);
WIRE 16 -1 (4075 2725)(4325 2725);
WIRE 16 -1 (4075 2725)(4075 2775);
WIRE 16 -1 (4075 2775)(4325 2775);
WIRE 16 -1 (4075 2775)(4075 2825);
WIRE 16 -1 (4075 2825)(4325 2825);
WIRE 16 -1 (4075 2825)(4075 2875);
WIRE 16 -1 (4075 2875)(4325 2875);
WIRE 16 -1 (4075 2875)(4075 2925);
WIRE 16 -1 (4325 2925)(4075 2925);
WIRE 16 -1 (4075 2925)(4075 2975);
WIRE 16 -1 (4075 2975)(4325 2975);
WIRE 16 -1 (4075 2975)(4075 3025);
WIRE 16 -1 (4075 3025)(4325 3025);
WIRE 16 -1 (4075 3025)(4075 3075);
WIRE 16 -1 (4075 3075)(4325 3075);
WIRE 16 -1 (4075 3075)(4075 3125);
WIRE 16 -1 (4075 3125)(4325 3125);
WIRE 16 -1 (4075 3125)(4075 3175);
WIRE 16 -1 (4075 3175)(4325 3175);
WIRE 16 -1 (4075 3175)(4075 3225);
WIRE 16 -1 (4075 3225)(4325 3225);
WIRE 16 -1 (4075 3225)(4075 3275);
WIRE 16 -1 (4075 3275)(4325 3275);
WIRE 16 -1 (4075 3275)(4075 3325);
WIRE 16 -1 (4075 3325)(4325 3325);
WIRE 16 -1 (4075 3325)(4075 3375);
WIRE 16 -1 (4075 3375)(4325 3375);
WIRE 16 -1 (4075 3375)(4075 3425);
WIRE 16 -1 (4325 3425)(4075 3425);
WIRE 16 -1 (4075 3425)(4075 3475);
WIRE 16 -1 (4075 3475)(4325 3475);
WIRE 16 -1 (4075 3475)(4075 3525);
WIRE 16 -1 (4075 3525)(4325 3525);
WIRE 16 -1 (4075 3525)(4075 3575);
WIRE 16 -1 (4075 3575)(4325 3575);
WIRE 16 -1 (4075 3575)(4075 3625);
WIRE 16 -1 (4075 3625)(4325 3625);
WIRE 16 -1 (4075 3625)(4075 3675);
WIRE 16 -1 (4075 3675)(4325 3675);
WIRE 16 -1 (4075 3675)(4075 3725);
WIRE 16 -1 (4075 3725)(4325 3725);
WIRE 16 -1 (4075 3725)(4075 3775);
WIRE 16 -1 (4075 3775)(4325 3775);
WIRE 16 -1 (4075 3775)(4075 3825);
WIRE 16 -1 (4075 3825)(4325 3825);
WIRE 16 -1 (4075 3825)(4075 3875);
WIRE 16 -1 (4075 3875)(4325 3875);
WIRE 16 -1 (4075 3875)(4075 3925);
WIRE 16 -1 (4325 3925)(4075 3925);
WIRE 16 -1 (4075 3925)(4075 3975);
WIRE 16 -1 (4075 3975)(4325 3975);
WIRE 16 -1 (4075 3975)(4075 4025);
WIRE 16 -1 (4325 4025)(4075 4025);
WIRE 16 -1 (5525 875)(5775 875);
WIRE 16 -1 (5525 925)(5775 925);
WIRE 16 -1 (5775 925)(5775 875);
WIRE 16 -1 (5775 1025)(5775 925);
WIRE 16 -1 (5525 1025)(5775 1025);
WIRE 16 -1 (5525 1075)(5775 1075);
WIRE 16 -1 (5775 1075)(5775 1025);
WIRE 16 -1 (5525 1125)(5775 1125);
WIRE 16 -1 (5775 1075)(5775 1125);
WIRE 16 -1 (5525 1175)(5775 1175);
WIRE 16 -1 (5775 1175)(5775 1125);
WIRE 16 -1 (5525 1225)(5775 1225);
WIRE 16 -1 (5775 1225)(5775 1175);
WIRE 16 -1 (5525 1275)(5775 1275);
WIRE 16 -1 (5775 1275)(5775 1225);
WIRE 16 -1 (5525 1325)(5775 1325);
WIRE 16 -1 (5775 1325)(5775 1275);
WIRE 16 -1 (5525 1375)(5775 1375);
WIRE 16 -1 (5775 1375)(5775 1325);
WIRE 16 -1 (5525 1425)(5775 1425);
WIRE 16 -1 (5775 1425)(5775 1375);
WIRE 16 -1 (5775 1475)(5525 1475);
WIRE 16 -1 (5775 1475)(5775 1425);
WIRE 16 -1 (5775 1525)(5525 1525);
WIRE 16 -1 (5775 1525)(5775 1475);
WIRE 16 -1 (5775 1575)(5525 1575);
WIRE 16 -1 (5775 1575)(5775 1525);
WIRE 16 -1 (5525 1625)(5775 1625);
WIRE 16 -1 (5775 1575)(5775 1625);
WIRE 16 -1 (5775 1675)(5525 1675);
WIRE 16 -1 (5775 1625)(5775 1675);
WIRE 16 -1 (5775 1725)(5525 1725);
WIRE 16 -1 (5775 1725)(5775 1675);
WIRE 16 -1 (5775 1775)(5525 1775);
WIRE 16 -1 (5775 1775)(5775 1725);
WIRE 16 -1 (5775 1825)(5525 1825);
WIRE 16 -1 (5775 1825)(5775 1775);
WIRE 16 -1 (5525 1875)(5775 1875);
WIRE 16 -1 (5775 1875)(5775 1825);
WIRE 16 -1 (5525 1925)(5775 1925);
WIRE 16 -1 (5775 1925)(5775 1875);
WIRE 16 -1 (5525 1975)(5775 1975);
WIRE 16 -1 (5775 1925)(5775 1975);
WIRE 16 -1 (5525 2025)(5775 2025);
WIRE 16 -1 (5775 2025)(5775 1975);
WIRE 16 -1 (5775 2075)(5775 2025);
WIRE 16 -1 (5525 2075)(5775 2075);
WIRE 16 -1 (5525 2125)(5775 2125);
WIRE 16 -1 (5775 2125)(5775 2075);
WIRE 16 -1 (5525 2175)(5775 2175);
WIRE 16 -1 (5775 2175)(5775 2125);
WIRE 16 -1 (5525 2225)(5775 2225);
WIRE 16 -1 (5775 2225)(5775 2175);
WIRE 16 -1 (5775 2275)(5525 2275);
WIRE 16 -1 (5775 2275)(5775 2225);
WIRE 16 -1 (5775 2325)(5525 2325);
WIRE 16 -1 (5775 2325)(5775 2275);
WIRE 16 -1 (5525 2375)(5775 2375);
WIRE 16 -1 (5775 2375)(5775 2325);
WIRE 16 -1 (5525 2425)(5775 2425);
WIRE 16 -1 (5775 2425)(5775 2375);
WIRE 16 -1 (5525 2475)(5775 2475);
WIRE 16 -1 (5775 2425)(5775 2475);
WIRE 16 -1 (5525 2525)(5775 2525);
WIRE 16 -1 (5775 2525)(5775 2475);
WIRE 16 -1 (5525 2575)(5775 2575);
WIRE 16 -1 (5775 2575)(5775 2525);
WIRE 16 -1 (5525 2625)(5775 2625);
WIRE 16 -1 (5775 2625)(5775 2575);
WIRE 16 -1 (5525 2675)(5775 2675);
WIRE 16 -1 (5775 2675)(5775 2625);
WIRE 16 -1 (5525 2725)(5775 2725);
WIRE 16 -1 (5775 2725)(5775 2675);
WIRE 16 -1 (5775 2775)(5525 2775);
WIRE 16 -1 (5775 2775)(5775 2725);
WIRE 16 -1 (5775 2825)(5525 2825);
WIRE 16 -1 (5775 2825)(5775 2775);
WIRE 16 -1 (5525 2875)(5775 2875);
WIRE 16 -1 (5775 2875)(5775 2825);
WIRE 16 -1 (5525 2925)(5775 2925);
WIRE 16 -1 (5775 2925)(5775 2875);
WIRE 16 -1 (5525 2975)(5775 2975);
WIRE 16 -1 (5775 2925)(5775 2975);
WIRE 16 -1 (5525 3025)(5775 3025);
WIRE 16 -1 (5775 3025)(5775 2975);
WIRE 16 -1 (5775 3075)(5775 3025);
WIRE 16 -1 (5525 3075)(5775 3075);
WIRE 16 -1 (5525 3125)(5775 3125);
WIRE 16 -1 (5775 3125)(5775 3075);
WIRE 16 -1 (5525 3175)(5775 3175);
WIRE 16 -1 (5775 3175)(5775 3125);
WIRE 16 -1 (5525 3225)(5775 3225);
WIRE 16 -1 (5775 3225)(5775 3175);
WIRE 16 -1 (5775 3275)(5525 3275);
WIRE 16 -1 (5775 3275)(5775 3225);
WIRE 16 -1 (5775 3325)(5525 3325);
WIRE 16 -1 (5775 3325)(5775 3275);
WIRE 16 -1 (5525 3375)(5775 3375);
WIRE 16 -1 (5775 3375)(5775 3325);
WIRE 16 -1 (5525 3425)(5775 3425);
WIRE 16 -1 (5775 3425)(5775 3375);
WIRE 16 -1 (5525 3475)(5775 3475);
WIRE 16 -1 (5775 3425)(5775 3475);
WIRE 16 -1 (5525 3525)(5775 3525);
WIRE 16 -1 (5775 3525)(5775 3475);
WIRE 16 -1 (5525 3575)(5775 3575);
WIRE 16 -1 (5775 3575)(5775 3525);
WIRE 16 -1 (5525 3625)(5775 3625);
WIRE 16 -1 (5775 3625)(5775 3575);
WIRE 16 -1 (5525 3675)(5775 3675);
WIRE 16 -1 (5775 3675)(5775 3625);
WIRE 16 -1 (5525 3725)(5775 3725);
WIRE 16 -1 (5775 3725)(5775 3675);
WIRE 16 -1 (5525 3775)(5775 3775);
WIRE 16 -1 (5775 3775)(5775 3725);
WIRE 16 -1 (5525 3825)(5775 3825);
WIRE 16 -1 (5775 3825)(5775 3775);
WIRE 16 -1 (5525 3875)(5775 3875);
WIRE 16 -1 (5775 3875)(5775 3825);
WIRE 16 -1 (5525 3925)(5775 3925);
WIRE 16 -1 (5775 3925)(5775 3875);
WIRE 16 -1 (5525 3975)(5775 3975);
WIRE 16 -1 (5775 3975)(5775 3925);
WIRE 16 -1 (5525 4025)(5775 4025);
WIRE 16 -1 (5775 4025)(5775 3975);
WIRE 16 -1 (5525 4075)(5775 4075);
WIRE 16 -1 (5775 4075)(5775 4025);
WIRE 16 -1 (5775 4125)(5775 4075);
WIRE 16 -1 (5525 4125)(5775 4125);
WIRE 16 -1 (5775 4175)(5775 4125);
WIRE 16 -1 (5525 4175)(5775 4175);
WIRE 16 -1 (-1775 225)(-2875 225);
FORCEPROP 2 LAST SIG_NAME PD_CHH_CPU0_DIMM2_SAA
J 0
(-2787 234);
DISPLAY 0.680851 (-2787 234);
PAINT WHITE (-2787 234);
WIRE 16 -1 (-1775 125)(-1775 225);
WIRE 16 -1 (2375 525)(2375 400);
WIRE 16 -1 (3000 525)(2375 525);
WIRE 16 -1 (3000 400)(3000 525);
WIRE 16 -1 (2375 50)(2375 200);
WIRE 16 -1 (3000 50)(2375 50);
WIRE 16 -1 (3000 50)(3000 200);
DOT 1 (2375 525);
DOT 1 (4075 2025);
DOT 1 (3000 50);
DOT 1 (4075 925);
DOT 1 (4075 975);
DOT 1 (4075 1025);
DOT 1 (4075 1075);
DOT 1 (4075 1125);
DOT 1 (4075 1175);
DOT 1 (4075 1225);
DOT 1 (4075 1275);
DOT 1 (4075 1325);
DOT 1 (4075 1375);
DOT 1 (4075 1425);
DOT 1 (4075 1475);
DOT 1 (4075 1525);
DOT 1 (4075 1575);
DOT 1 (4075 1625);
DOT 1 (4075 1675);
DOT 1 (4075 1725);
DOT 1 (4075 1775);
DOT 1 (4075 1825);
DOT 1 (4075 1875);
DOT 1 (4075 1925);
DOT 1 (4075 1975);
DOT 1 (4075 2075);
DOT 1 (4075 2125);
DOT 1 (4075 2175);
DOT 1 (4075 2225);
DOT 1 (4075 2275);
DOT 1 (4075 2325);
DOT 1 (4075 2375);
DOT 1 (4075 2425);
DOT 1 (4075 2475);
DOT 1 (4075 2525);
DOT 1 (4075 2575);
DOT 1 (4075 2625);
DOT 1 (4075 2675);
DOT 1 (4075 2725);
DOT 1 (4075 2775);
DOT 1 (4075 2825);
DOT 1 (4075 2875);
DOT 1 (4075 2925);
DOT 1 (4075 2975);
DOT 1 (4075 3025);
DOT 1 (4075 3075);
DOT 1 (4075 3125);
DOT 1 (4075 3175);
DOT 1 (4075 3225);
DOT 1 (4075 3275);
DOT 1 (4075 3325);
DOT 1 (4075 3375);
DOT 1 (4075 3425);
DOT 1 (4075 3475);
DOT 1 (4075 3525);
DOT 1 (4075 3575);
DOT 1 (4075 3625);
DOT 1 (4075 3675);
DOT 1 (4075 3725);
DOT 1 (4075 3775);
DOT 1 (4075 3825);
DOT 1 (4075 3875);
DOT 1 (4075 3925);
DOT 1 (4075 3975);
DOT 1 (4075 4175);
DOT 1 (4075 4125);
DOT 1 (5775 1025);
DOT 1 (5775 1075);
DOT 1 (5775 1125);
DOT 1 (5775 1175);
DOT 1 (5775 1225);
DOT 1 (5775 1275);
DOT 1 (5775 1325);
DOT 1 (5775 1375);
DOT 1 (5775 1425);
DOT 1 (5775 1475);
DOT 1 (5775 1525);
DOT 1 (5775 1625);
DOT 1 (5775 1575);
DOT 1 (5775 1675);
DOT 1 (5775 1725);
DOT 1 (5775 1775);
DOT 1 (5775 1825);
DOT 1 (5775 1875);
DOT 1 (5775 1925);
DOT 1 (5775 1975);
DOT 1 (5775 2025);
DOT 1 (5775 2075);
DOT 1 (5775 2125);
DOT 1 (5775 2175);
DOT 1 (5775 2225);
DOT 1 (5775 2275);
DOT 1 (5775 2325);
DOT 1 (5775 2375);
DOT 1 (5775 2425);
DOT 1 (5775 2475);
DOT 1 (5775 2525);
DOT 1 (5775 2575);
DOT 1 (5775 2625);
DOT 1 (5775 2675);
DOT 1 (5775 2725);
DOT 1 (5775 2775);
DOT 1 (5775 2825);
DOT 1 (5775 2875);
DOT 1 (5775 2925);
DOT 1 (5775 3025);
DOT 1 (5775 2975);
DOT 1 (5775 3075);
DOT 1 (5775 3125);
DOT 1 (5775 3175);
DOT 1 (5775 3225);
DOT 1 (5775 3275);
DOT 1 (5775 3325);
DOT 1 (5775 3375);
DOT 1 (5775 3425);
DOT 1 (5775 3475);
DOT 1 (5775 3525);
DOT 1 (5775 3575);
DOT 1 (5775 3675);
DOT 1 (5775 3625);
DOT 1 (5775 3725);
DOT 1 (5775 3775);
DOT 1 (5775 3825);
DOT 1 (5775 3875);
DOT 1 (5775 3925);
DOT 1 (5775 3975);
DOT 1 (5775 4025);
DOT 1 (5775 4075);
DOT 1 (5775 4125);
DOT 1 (5775 925);
DOT 1 (5775 875);
DOT 1 (5775 825);
FORCENOTE
20210728 MODIFY FOR GT
(-3150 4825) 0;
DISPLAY LEFT (-3150 4825);
DISPLAY 2.510638 (-3150 4825);
PAINT PINK (-3150 4825);
QUIT
